G04 ================== begin FILE IDENTIFICATION RECORD ==================*
G04 Layout Name:  15968-1a.brd*
G04 Film Name:    DP_REF_L3*
G04 File Format:  Gerber RS274X*
G04 File Origin:  Cadence Allegro 16.5-S058*
G04 Origin Date:  Fri Oct 14 10:23:49 2016*
G04 *
G04 Layer:  BOARD GEOMETRY/DP_REF_L3_TBL*
G04 Layer:  BOARD GEOMETRY/DP_REF_L3_L3*
G04 Layer:  BOARD GEOMETRY/PANEL_OUTLINE*
G04 *
G04 Offset:    (0.00 0.00)*
G04 Mirror:    No*
G04 Mode:      Positive*
G04 Rotation:  0*
G04 FullContactRelief:  No*
G04 UndefLineWidth:     6.00*
G04 ================== end FILE IDENTIFICATION RECORD ====================*
%FSLAX35Y35*MOIN*%
%IR0*IPPOS*OFA0.00000B0.00000*MIA0B0*SFA1.00000B1.00000*%
%ADD10C,.02*%
%ADD11C,.005*%
%ADD12C,.006*%
G75*
%LPD*%
G75*
G54D10*
G01X687653Y496146D02*
X1212653D01*
G01X687653Y461496D02*
X1212653D01*
G01X687653Y426846D02*
X1212653D01*
G01X687653Y530796D02*
Y426846D01*
G01Y530796D02*
X1212653D01*
G01X862653D02*
Y426846D01*
G01X1107653Y530796D02*
Y426846D01*
G01X1212653Y530796D02*
Y426846D01*
G54D11*
G01X-21653Y-58346D02*
G03X-6653Y-73346I15000J0D01*
G01X65080D02*
X-6653D01*
G01X9506Y0D02*
X69017D01*
G01X6722Y1153D02*
G03X9506Y0I2784J2784D01*
G01X1154Y6721D02*
X6722Y1153D01*
G01X1Y9505D02*
G03X1154Y6721I3937J0D01*
G01X1Y238051D02*
Y9505D01*
G01Y238051D02*
Y9505D01*
G01X-21653Y238051D02*
Y9505D01*
G01X1D02*
G03X1154Y6721I3937J0D01*
G01X-7873Y9505D02*
G03X-4414Y1153I11811J-1D01*
G01X1154Y6721D02*
X6722Y1153D01*
G01X-4414D02*
X1154Y-4415D01*
G01X6722Y1153D02*
G03X9506Y0I2784J2784D01*
G01X1154Y-4415D02*
G03X9506Y-7874I8351J8352D01*
G01Y0D02*
X69017D01*
G01X9506Y-7874D02*
X14917D01*
G01X-21653Y9505D02*
Y-58346D01*
G01X14917Y-7874D02*
G03Y0I0J3937D01*
G01X-7873Y50852D02*
Y9505D01*
G01Y81561D02*
G03X1I3937J-1D01*
G01Y50852D02*
G03X-7873I-3937J0D01*
G01Y186482D02*
Y81561D01*
G01X13443Y249862D02*
X611812D01*
G01X10659Y251015D02*
G03X13443Y249862I2784J2784D01*
G01X1154Y260520D02*
X10659Y251015D01*
G01X3938Y241988D02*
G03X1Y238051I0J-3937D01*
G01X602307Y241988D02*
X3938D01*
G01X602307D02*
X3938D01*
G01D02*
G03X1Y238051I0J-3937D01*
G01X-7873D02*
Y217191D01*
G01X1154Y260520D02*
X10659Y251015D01*
G01D02*
G03X13443Y249862I2784J2784D01*
G01D02*
X611812D01*
G01X-21653Y238051D02*
Y534327D01*
G01X-7873Y238051D02*
Y263304D01*
G01Y217191D02*
G03X1I3937J-1D01*
G01Y186482D02*
G03X-7873I-3937J0D01*
G01X1Y263304D02*
G03X1154Y260520I3937J0D01*
G01X1Y328602D02*
Y263304D01*
G01X3938Y332539D02*
G03X1Y328602I0J-3937D01*
G01X53151Y332539D02*
X3938D01*
G01X53151D02*
X3938D01*
G01D02*
G03X1Y328602I0J-3937D01*
G01X3938Y340413D02*
G03X-7873Y328602I0J-11811D01*
G01X1D02*
Y263304D01*
G01X-7873Y328602D02*
Y263304D01*
G01X1D02*
G03X1154Y260520I3937J0D01*
G01X10965Y332539D02*
G03Y340413I0J3937D01*
G01D02*
X3938D01*
G01X-6653Y565196D02*
G03X-21653Y550196I0J-15000D01*
G01X67796Y565196D02*
X-6653D01*
G01X-21653Y542201D02*
Y550196D01*
G01Y534327D02*
G03Y542201I0J3937D01*
G01X74922Y-73346D02*
X175828D01*
G01X72954Y-71378D02*
X74922Y-73346D01*
G01X72954Y-3937D02*
Y-71378D01*
G01X65080Y-7874D02*
Y-71772D01*
G01D02*
Y-73346D01*
G01X72954Y-3937D02*
G03X69017Y0I-3937J0D01*
G01X72954Y-3937D02*
G03X69017Y0I-3937J0D01*
G01X45626D02*
G03Y-7874I0J-3937D01*
G01D02*
X65080D01*
G01X51397Y241988D02*
G03Y249862I0J3937D01*
G01X93906D02*
G03Y241988I0J-3937D01*
G01X53151Y332539D02*
G03X57088Y336476I0J3937D01*
G01Y482345D02*
Y336476D01*
G01Y482345D02*
Y336476D01*
G01X53151Y332539D02*
G03X57088Y336476I0J3937D01*
G01X41674Y340413D02*
G03Y332539I0J-3937D01*
G01X49214Y340413D02*
X41674D01*
G01X49214Y442487D02*
Y340413D01*
G01X67796Y565196D02*
Y499724D01*
G01X75670Y563228D02*
Y495787D01*
G01X58241Y485129D02*
G03X57088Y482345I2784J-2784D01*
G01X63808Y490697D02*
X58241Y485129D01*
G01X66592Y491850D02*
G03X63808Y490697I0J-3937D01*
G01X71733Y491850D02*
X66592D01*
G01X71733D02*
G03X75670Y495787I0J3937D01*
G01X67796Y499724D02*
X66592D01*
G01Y491850D02*
G03X63808Y490697I0J-3937D01*
G01X66592Y499724D02*
G03X58240Y496265I-1J-11811D01*
G01X63808Y490697D02*
X58241Y485129D01*
G01X58240Y496264D02*
X52673Y490696D01*
G01X58241Y485129D02*
G03X57088Y482345I2784J-2784D01*
G01X52673Y490697D02*
G03X49214Y482343I8352J-8351D01*
G01Y482345D02*
Y473195D01*
G01X57088Y442487D02*
G03X49214I-3937J-1D01*
G01Y473195D02*
G03X57088I3937J0D01*
G01X77639Y565196D02*
X75670Y563228D01*
G01X173111Y565196D02*
X77639D01*
G01X177796Y-71378D02*
Y-52874D01*
G01X175828Y-73346D02*
X177796Y-71378D01*
G01X187245Y-52874D02*
G03X177796I-4725J0D01*
G01X183615Y213593D02*
X183614D01*
G01X184131Y214621D02*
X184577Y214399D01*
G01X183619Y213591D02*
X183615Y213593D01*
G01X184131Y214621D02*
X184577Y214399D01*
G01X183884Y213458D02*
X183619Y213591D01*
G01X184131Y214621D02*
X184577Y214399D01*
G01X184130Y214621D02*
X184131D01*
G01X184888Y210871D02*
G03X183884Y213458I-3837J-1D01*
G01X184577Y214399D02*
G02X186038Y210872I-3527J-3527D01*
G01X184888Y209322D02*
Y210871D01*
G01X186038Y210872D02*
Y209608D01*
G01X185631Y207919D02*
X184888Y209322D01*
G01X186038Y209608D02*
X186629Y208494D01*
G01X186426Y206647D02*
X185631Y207919D01*
G01X186629Y208494D02*
X201764Y184257D01*
G01X186629Y208494D02*
X201764Y184257D01*
G01X186629Y208494D02*
X201764Y184257D01*
G01X186629Y208494D02*
X201764Y184257D01*
G01X186629Y208494D02*
X201764Y184257D01*
G01X186426Y206647D02*
X185631Y207919D01*
G01X186038Y209608D02*
X186629Y208494D01*
G01X185631Y207919D02*
X184888Y209322D01*
G01X186038Y210872D02*
Y209608D01*
G01X184888Y209322D02*
Y210871D01*
G01X184577Y214399D02*
G02X186038Y210872I-3527J-3527D01*
G01X184888Y210871D02*
G03X183884Y213458I-3837J-1D01*
G01X184131Y214621D02*
X184577Y214399D01*
G01X183615Y213593D02*
X183614D01*
G01X183619Y213591D02*
X183615Y213593D01*
G01X183884Y213458D02*
X183619Y213591D01*
G01X184130Y214621D02*
X184131D01*
G01X183884Y213458D02*
X183619Y213591D01*
G01X175080Y563228D02*
X173111Y565196D01*
G01X175080Y534488D02*
Y563228D01*
G01Y534488D02*
G03X175867Y533700I787J-1D01*
G01X209529D02*
X175867D01*
G01X189214Y-73346D02*
X403466D01*
G01X187245Y-71378D02*
X189214Y-73346D01*
G01X187245Y-52874D02*
Y-71378D01*
G01X267042Y63078D02*
X314339Y-4471D01*
G01X250296Y112256D02*
X267042Y63078D01*
G01X251418Y112531D02*
X268078Y63604D01*
G01X249471Y74201D02*
X232066Y128227D01*
G01X250513Y74719D02*
X233216Y128408D01*
G01X308457Y-10040D02*
X249471Y74201D01*
G01X309283Y-9214D02*
X250513Y74719D01*
G01X231519Y86190D02*
X216608Y126787D01*
G01X217723Y127088D02*
X232547Y86727D01*
G01X302179Y-14725D02*
X231519Y86190D01*
G01X232547Y86727D02*
X303121Y-14065D01*
G01X267042Y63078D02*
X314339Y-4471D01*
G01X251418Y112531D02*
X268078Y63604D01*
G01X250296Y112256D02*
X267042Y63078D01*
G01X250513Y74719D02*
X233216Y128408D01*
G01X249471Y74201D02*
X232066Y128227D01*
G01X309283Y-9214D02*
X250513Y74719D01*
G01X308457Y-10040D02*
X249471Y74201D01*
G01X232547Y86727D02*
X303121Y-14065D01*
G01X302179Y-14725D02*
X231519Y86190D01*
G01X217723Y127088D02*
X232547Y86727D01*
G01X231519Y86190D02*
X216608Y126787D01*
G01X253338Y77442D02*
X241570Y114557D01*
G01X254400Y77900D02*
X242700Y114800D01*
G01X258510Y68124D02*
X253338Y77442D01*
G01X259515Y68683D02*
X254400Y77900D01*
G01X311035Y-6903D02*
X258426Y68232D01*
G01X311861Y-6077D02*
X259515Y68683D01*
G01X240639Y79814D02*
X305086Y-12224D01*
G01X241728Y80265D02*
X305912Y-11398D01*
G01X239404Y86818D02*
X240639Y79814D01*
G01X240533Y87042D02*
X241728Y80265D01*
G01X238857Y89305D02*
X239404Y86818D01*
G01X239963Y89633D02*
X240533Y87042D01*
G01X224191Y128331D02*
X238857Y89305D01*
G01X225341Y128540D02*
X239963Y89633D01*
G01X254400Y77900D02*
X242700Y114800D01*
G01X253338Y77442D02*
X241570Y114557D01*
G01X259515Y68683D02*
X254400Y77900D01*
G01X258510Y68124D02*
X253338Y77442D01*
G01X311861Y-6077D02*
X259515Y68683D01*
G01X311035Y-6903D02*
X258426Y68232D01*
G01X241728Y80265D02*
X305912Y-11398D01*
G01X240639Y79814D02*
X305086Y-12224D01*
G01X240533Y87042D02*
X241728Y80265D01*
G01X239404Y86818D02*
X240639Y79814D01*
G01X239963Y89633D02*
X240533Y87042D01*
G01X238857Y89305D02*
X239404Y86818D01*
G01X225341Y128540D02*
X239963Y89633D01*
G01X224191Y128331D02*
X238857Y89305D01*
G01X222683Y91171D02*
X208918Y126015D01*
G01X210068Y126234D02*
X223703Y91720D01*
G01X299182Y-18087D02*
X222683Y91171D01*
G01X223703Y91720D02*
X300124Y-17427D01*
G01X223703Y91720D02*
X300124Y-17427D01*
G01X299182Y-18087D02*
X222683Y91171D01*
G01X210068Y126234D02*
X223703Y91720D01*
G01X222683Y91171D02*
X208918Y126015D01*
G01X257947Y188838D02*
X268300Y168900D01*
G01X258900Y189500D02*
X269374Y169330D01*
G01X258900Y189500D02*
X269374Y169330D01*
G01X257947Y188838D02*
X268300Y168900D01*
G01X261132Y162979D02*
X232182Y208012D01*
G01X261399Y164692D02*
X241819Y195149D01*
G01X262156Y163514D02*
X261399Y164692D01*
G01X263076Y158272D02*
X261132Y162979D01*
G01X264154Y158675D02*
X262156Y163514D01*
G01X263166Y158004D02*
X263076Y158272D01*
G01X264269Y158332D02*
X264154Y158675D01*
G01X263560Y156482D02*
X263166Y158004D01*
G01X264671Y156780D02*
X264269Y158332D01*
G01X261952Y152684D02*
G03X263553Y156442I-3871J3869D01*
G01X264704Y156419D02*
G03Y156663I-6623J122D01*
G01X262765Y151870D02*
G03X264704Y156419I-4684J4684D01*
G01X261625Y152358D02*
X261952Y152684D01*
G01X262437Y151543D02*
X262765Y151870D01*
G01X261624Y152357D02*
X261625Y152358D01*
G01X262437Y151543D02*
X262765Y151870D01*
G01X259671Y147640D02*
G02X261624Y152357I6669J1D01*
G01X260821Y147640D02*
G02X262437Y151543I5519J1D01*
G01X259671Y139144D02*
Y147640D01*
G01X260821Y139145D02*
Y147640D01*
G01X262120Y133230D02*
G02X259671Y139144I5916J5914D01*
G01X262934Y134044D02*
G02X260821Y139145I5101J5101D01*
G01X262648Y132702D02*
X262120Y133230D01*
G01X263462Y133516D02*
X262934Y134044D01*
G01X263560Y130500D02*
G03X262648Y132702I-3114J0D01*
G01X264711Y130500D02*
G03X263462Y133516I-4266J0D01*
G01X263560Y129270D02*
Y130500D01*
G01X264711Y128540D02*
Y130500D01*
G01X263561Y128437D02*
Y128965D01*
G01X264711Y128540D02*
Y130500D01*
G01X276176Y56888D02*
X263561Y128437D01*
G01X264795Y128064D02*
X264711Y128540D01*
G01X277265Y57339D02*
X264795Y128062D01*
G01X261132Y162979D02*
X232182Y208012D01*
G01X261132Y162979D02*
X232182Y208012D01*
G01X261132Y162979D02*
X232182Y208012D01*
G01X261132Y162979D02*
X232182Y208012D01*
G01X261399Y164692D02*
X241819Y195149D01*
G01X261132Y162979D02*
X232182Y208012D01*
G01X262156Y163514D02*
X261399Y164692D01*
G01X261132Y162979D02*
X232182Y208012D01*
G01X264154Y158675D02*
X262156Y163514D01*
G01X263076Y158272D02*
X261132Y162979D01*
G01X264269Y158332D02*
X264154Y158675D01*
G01X263166Y158004D02*
X263076Y158272D01*
G01X264671Y156780D02*
X264269Y158332D01*
G01X263560Y156482D02*
X263166Y158004D01*
G01X264704Y156419D02*
G03Y156663I-6623J122D01*
G01X261952Y152684D02*
G03X263553Y156442I-3871J3869D01*
G01X262765Y151870D02*
G03X264704Y156419I-4684J4684D01*
G01X261952Y152684D02*
G03X263553Y156442I-3871J3869D01*
G01X262437Y151543D02*
X262765Y151870D01*
G01X261625Y152358D02*
X261952Y152684D01*
G01X261624Y152357D02*
X261625Y152358D01*
G01X260821Y147640D02*
G02X262437Y151543I5519J1D01*
G01X259671Y147640D02*
G02X261624Y152357I6669J1D01*
G01X260821Y139145D02*
Y147640D01*
G01X259671Y139144D02*
Y147640D01*
G01X262934Y134044D02*
G02X260821Y139145I5101J5101D01*
G01X262120Y133230D02*
G02X259671Y139144I5916J5914D01*
G01X263462Y133516D02*
X262934Y134044D01*
G01X262648Y132702D02*
X262120Y133230D01*
G01X264711Y130500D02*
G03X263462Y133516I-4266J0D01*
G01X263560Y130500D02*
G03X262648Y132702I-3114J0D01*
G01X264711Y128540D02*
Y130500D01*
G01X263560Y129270D02*
Y130500D01*
G01X263561Y128437D02*
Y128965D01*
G01X264795Y128064D02*
X264711Y128540D01*
G01X276176Y56888D02*
X263561Y128437D01*
G01X277265Y57339D02*
X264795Y128062D01*
G01X276176Y56888D02*
X263561Y128437D01*
G01X247811Y128452D02*
X250296Y112256D01*
G01X248961Y128540D02*
X251418Y112531D01*
G01X247811Y128965D02*
Y128452D01*
G01X248961Y130500D02*
Y128540D01*
G01X247810Y130500D02*
Y129270D01*
G01X248961Y130500D02*
Y128540D01*
G01X246898Y132702D02*
G02X247810Y130500I-2202J-2202D01*
G01X247712Y133516D02*
G02X248961Y130500I-3017J-3016D01*
G01X246370Y133230D02*
X246898Y132702D01*
G01X247184Y134044D02*
X247712Y133516D01*
G01X243921Y139144D02*
G03X246370Y133230I8365J0D01*
G01X245071Y139145D02*
G03X247184Y134044I7214J0D01*
G01X243921Y147640D02*
Y139144D01*
G01X245071Y147640D02*
Y139145D01*
G01X245874Y152357D02*
G03X243921Y147640I4716J-4716D01*
G01X246687Y151543D02*
G03X245071Y147640I3903J-3902D01*
G01X246202Y152684D02*
X245874Y152357D01*
G01X247015Y151870D02*
X246687Y151543D01*
G01X247804Y156554D02*
G02X246202Y152684I-5473J-1D01*
G01X248955Y156554D02*
G02X247015Y151870I-6624J0D01*
G01X247815Y157543D02*
X247804Y156554D01*
G01X248968Y157729D02*
X248955Y156554D01*
G01X237909Y186448D02*
X247815Y157543D01*
G01X238962Y186931D02*
X248968Y157729D01*
G01X225275Y176677D02*
X223416Y180592D01*
G01X226314Y177170D02*
X224413Y181175D01*
G01X227138Y172749D02*
X225275Y176677D01*
G01X228204Y173186D02*
X226314Y177170D01*
G01X228623Y168492D02*
X227138Y172749D01*
G01X229700Y168900D02*
X228204Y173186D01*
G01X232060Y158019D02*
X228623Y168492D01*
G01X233210Y158203D02*
X229700Y168900D01*
G01X232060Y156553D02*
Y158019D01*
G01X233210Y156554D02*
Y158203D01*
G01X230457Y152685D02*
G03X232059Y156554I-3871J3869D01*
G01X231270Y151870D02*
G03X233210Y156554I-4684J4684D01*
G01X230294Y152523D02*
X230457Y152685D01*
G01X230942Y151543D02*
X231270Y151870D01*
G01X230129Y152357D02*
X230294Y152523D01*
G01X230942Y151543D02*
X231270Y151870D01*
G01X228176Y147640D02*
G02X230129Y152357I6669J1D01*
G01X229326Y147640D02*
G02X230942Y151543I5519J1D01*
G01X228176Y139144D02*
Y147640D01*
G01X229326Y139145D02*
Y147640D01*
G01X230625Y133230D02*
G02X228176Y139144I5916J5914D01*
G01X231439Y134044D02*
G02X229326Y139145I5101J5101D01*
G01X231153Y132702D02*
X230625Y133230D01*
G01X231967Y133516D02*
X231439Y134044D01*
G01X232065Y130500D02*
G03X231153Y132702I-3114J0D01*
G01X233216Y130500D02*
G03X231967Y133516I-4266J0D01*
G01X232066Y128227D02*
Y129885D01*
G01X233216Y128408D02*
Y130500D01*
G01X212184Y175235D02*
X193646Y203557D01*
G01X213147Y175865D02*
X213219Y175754D01*
G01X201724Y193318D02*
X213147Y175865D01*
G01X213193Y172474D02*
X212184Y175235D01*
G01X213219Y175754D02*
X214301Y172795D01*
G01X216310Y158093D02*
X213193Y172474D01*
G01X214301Y172795D02*
X217460Y158217D01*
G01X216310Y156553D02*
Y158093D01*
G01X217460Y158217D02*
Y156554D01*
G01X214707Y152685D02*
G03X216309Y156554I-3871J3869D01*
G01X217460D02*
G02X215520Y151870I-6624J0D01*
G01X214544Y152523D02*
X214707Y152685D01*
G01X215520Y151870D02*
X215192Y151543D01*
G01X214379Y152357D02*
X214544Y152523D01*
G01X215520Y151870D02*
X215192Y151543D01*
G01X212426Y147640D02*
G02X214379Y152357I6669J1D01*
G01X215192Y151543D02*
G03X213576Y147640I3903J-3902D01*
G01X212426Y139144D02*
Y147640D01*
G01X213576D02*
Y139145D01*
G01X214875Y133230D02*
G02X212426Y139144I5916J5914D01*
G01X213576Y139145D02*
G03X215689Y134044I7214J0D01*
G01X215403Y132702D02*
X214875Y133230D01*
G01X215689Y134044D02*
X216217Y133516D01*
G01X216315Y130500D02*
G03X215403Y132702I-3114J0D01*
G01X216217Y133516D02*
G02X217466Y130500I-3017J-3016D01*
G01X216315Y129270D02*
Y130500D01*
G01X217466D02*
Y128540D01*
G01X216316Y128439D02*
Y128965D01*
G01X217466Y130500D02*
Y128540D01*
G01X216608Y126787D02*
X216316Y128439D01*
G01X217466Y128540D02*
X217723Y127088D01*
G01X248961Y128540D02*
X251418Y112531D01*
G01X247811Y128452D02*
X250296Y112256D01*
G01X248961Y130500D02*
Y128540D01*
G01X247811Y128965D02*
Y128452D01*
G01X247810Y130500D02*
Y129270D01*
G01X247712Y133516D02*
G02X248961Y130500I-3017J-3016D01*
G01X246898Y132702D02*
G02X247810Y130500I-2202J-2202D01*
G01X247184Y134044D02*
X247712Y133516D01*
G01X246370Y133230D02*
X246898Y132702D01*
G01X245071Y139145D02*
G03X247184Y134044I7214J0D01*
G01X243921Y139144D02*
G03X246370Y133230I8365J0D01*
G01X245071Y147640D02*
Y139145D01*
G01X243921Y147640D02*
Y139144D01*
G01X246687Y151543D02*
G03X245071Y147640I3903J-3902D01*
G01X245874Y152357D02*
G03X243921Y147640I4716J-4716D01*
G01X247015Y151870D02*
X246687Y151543D01*
G01X246202Y152684D02*
X245874Y152357D01*
G01X248955Y156554D02*
G02X247015Y151870I-6624J0D01*
G01X247804Y156554D02*
G02X246202Y152684I-5473J-1D01*
G01X248968Y157729D02*
X248955Y156554D01*
G01X247815Y157543D02*
X247804Y156554D01*
G01X238962Y186931D02*
X248968Y157729D01*
G01X237909Y186448D02*
X247815Y157543D01*
G01X226314Y177170D02*
X224413Y181175D01*
G01X225275Y176677D02*
X223416Y180592D01*
G01X228204Y173186D02*
X226314Y177170D01*
G01X227138Y172749D02*
X225275Y176677D01*
G01X229700Y168900D02*
X228204Y173186D01*
G01X228623Y168492D02*
X227138Y172749D01*
G01X233210Y158203D02*
X229700Y168900D01*
G01X232060Y158019D02*
X228623Y168492D01*
G01X233210Y156554D02*
Y158203D01*
G01X232060Y156553D02*
Y158019D01*
G01X231270Y151870D02*
G03X233210Y156554I-4684J4684D01*
G01X230457Y152685D02*
G03X232059Y156554I-3871J3869D01*
G01X230942Y151543D02*
X231270Y151870D01*
G01X230294Y152523D02*
X230457Y152685D01*
G01X230129Y152357D02*
X230294Y152523D01*
G01X229326Y147640D02*
G02X230942Y151543I5519J1D01*
G01X228176Y147640D02*
G02X230129Y152357I6669J1D01*
G01X229326Y139145D02*
Y147640D01*
G01X228176Y139144D02*
Y147640D01*
G01X231439Y134044D02*
G02X229326Y139145I5101J5101D01*
G01X230625Y133230D02*
G02X228176Y139144I5916J5914D01*
G01X231967Y133516D02*
X231439Y134044D01*
G01X231153Y132702D02*
X230625Y133230D01*
G01X233216Y130500D02*
G03X231967Y133516I-4266J0D01*
G01X232065Y130500D02*
G03X231153Y132702I-3114J0D01*
G01X233216Y128408D02*
Y130500D01*
G01X232066Y128227D02*
Y129885D01*
G01X217466Y128540D02*
X217723Y127088D01*
G01X216608Y126787D02*
X216316Y128439D01*
G01X217466Y130500D02*
Y128540D01*
G01X216315Y129270D02*
Y130500D01*
G01X216316Y128439D02*
Y128965D01*
G01X216217Y133516D02*
G02X217466Y130500I-3017J-3016D01*
G01X216315D02*
G03X215403Y132702I-3114J0D01*
G01X215689Y134044D02*
X216217Y133516D01*
G01X215403Y132702D02*
X214875Y133230D01*
G01X213576Y139145D02*
G03X215689Y134044I7214J0D01*
G01X214875Y133230D02*
G02X212426Y139144I5916J5914D01*
G01X213576Y147640D02*
Y139145D01*
G01X212426Y139144D02*
Y147640D01*
G01X215192Y151543D02*
G03X213576Y147640I3903J-3902D01*
G01X212426D02*
G02X214379Y152357I6669J1D01*
G01X215520Y151870D02*
X215192Y151543D01*
G01X214544Y152523D02*
X214707Y152685D01*
G01X214379Y152357D02*
X214544Y152523D01*
G01X217460Y156554D02*
G02X215520Y151870I-6624J0D01*
G01X214707Y152685D02*
G03X216309Y156554I-3871J3869D01*
G01X217460Y158217D02*
Y156554D01*
G01X216310Y156553D02*
Y158093D01*
G01X214301Y172795D02*
X217460Y158217D01*
G01X216310Y158093D02*
X213193Y172474D01*
G01X213219Y175754D02*
X214301Y172795D01*
G01X213193Y172474D02*
X212184Y175235D01*
G01X213147Y175865D02*
X213219Y175754D01*
G01X212184Y175235D02*
X193646Y203557D01*
G01X201724Y193318D02*
X213147Y175865D01*
G01X212184Y175235D02*
X193646Y203557D01*
G01X212184Y175235D02*
X193646Y203557D01*
G01X212184Y175235D02*
X193646Y203557D01*
G01X212184Y175235D02*
X193646Y203557D01*
G01X234995Y175181D02*
X229223Y186305D01*
G01X236069Y175609D02*
X230142Y187031D01*
G01X239930Y158040D02*
X234995Y175181D01*
G01X241080Y158203D02*
X236100Y175500D01*
G01X239930Y156553D02*
Y158040D01*
G01X241080Y156554D02*
Y158203D01*
G01X238327Y152685D02*
G03X239929Y156554I-3871J3869D01*
G01X239140Y151870D02*
G03X241080Y156554I-4684J4684D01*
G01X238164Y152523D02*
X238327Y152685D01*
G01X238812Y151543D02*
X239140Y151870D01*
G01X237999Y152357D02*
X238164Y152523D01*
G01X238812Y151543D02*
X239140Y151870D01*
G01X236046Y147640D02*
G02X237999Y152357I6669J1D01*
G01X237196Y147640D02*
G02X238812Y151543I5519J1D01*
G01X236046Y139144D02*
Y147640D01*
G01X237196Y139145D02*
Y147640D01*
G01X238495Y133230D02*
G02X236046Y139144I5916J5914D01*
G01X239309Y134044D02*
G02X237196Y139145I5101J5101D01*
G01X239023Y132702D02*
X238495Y133230D01*
G01X239837Y133516D02*
X239309Y134044D01*
G01X239935Y130500D02*
G03X239023Y132702I-3114J0D01*
G01X241086Y130500D02*
G03X239837Y133516I-4266J0D01*
G01X239935Y129270D02*
Y130500D01*
G01X241086Y128540D02*
Y130500D01*
G01X239936Y128472D02*
Y128965D01*
G01X241086Y128540D02*
Y130500D01*
G01X241570Y114557D02*
X239936Y128472D01*
G01X242700Y114800D02*
X241086Y128540D01*
G01X224191Y128965D02*
Y128331D01*
G01X225341Y130500D02*
Y128540D01*
G01X224190Y130500D02*
Y129270D01*
G01X225341Y130500D02*
Y128540D01*
G01X223278Y132702D02*
G02X224190Y130500I-2202J-2202D01*
G01X224092Y133516D02*
G02X225341Y130500I-3017J-3016D01*
G01X222750Y133230D02*
X223278Y132702D01*
G01X223564Y134044D02*
X224092Y133516D01*
G01X220301Y139144D02*
G03X222750Y133230I8365J0D01*
G01X221451Y139145D02*
G03X223564Y134044I7214J0D01*
G01X220301Y147640D02*
Y139144D01*
G01X221451Y147640D02*
Y139145D01*
G01X222254Y152357D02*
G03X220301Y147640I4716J-4716D01*
G01X223067Y151543D02*
G03X221451Y147640I3903J-3902D01*
G01X222419Y152523D02*
X222254Y152357D01*
G01X223395Y151870D02*
X223067Y151543D01*
G01X222582Y152685D02*
X222419Y152523D01*
G01X223395Y151870D02*
X223067Y151543D01*
G01X224184Y156554D02*
G02X222582Y152685I-5473J0D01*
G01X225332Y156722D02*
G02X223395Y151870I-6622J-169D01*
G01X223800Y157900D02*
X224184Y156554D01*
G01X224906Y158216D02*
X225332Y156722D01*
G01X224845Y158430D02*
X224905Y158220D01*
G01X223745Y158091D02*
X223797Y157908D01*
G01X224845Y158430D02*
X224905Y158220D01*
G01X218241Y174738D02*
X223745Y158091D01*
G01X219300Y175200D02*
X224845Y158430D01*
G01X208496Y192417D02*
X218241Y174738D01*
G01X209479Y193019D02*
X219300Y175200D01*
G01X236069Y175609D02*
X230142Y187031D01*
G01X234995Y175181D02*
X229223Y186305D01*
G01X241080Y158203D02*
X236100Y175500D01*
G01X239930Y158040D02*
X234995Y175181D01*
G01X241080Y156554D02*
Y158203D01*
G01X239930Y156553D02*
Y158040D01*
G01X239140Y151870D02*
G03X241080Y156554I-4684J4684D01*
G01X238327Y152685D02*
G03X239929Y156554I-3871J3869D01*
G01X238812Y151543D02*
X239140Y151870D01*
G01X238164Y152523D02*
X238327Y152685D01*
G01X237999Y152357D02*
X238164Y152523D01*
G01X237196Y147640D02*
G02X238812Y151543I5519J1D01*
G01X236046Y147640D02*
G02X237999Y152357I6669J1D01*
G01X237196Y139145D02*
Y147640D01*
G01X236046Y139144D02*
Y147640D01*
G01X239309Y134044D02*
G02X237196Y139145I5101J5101D01*
G01X238495Y133230D02*
G02X236046Y139144I5916J5914D01*
G01X239837Y133516D02*
X239309Y134044D01*
G01X239023Y132702D02*
X238495Y133230D01*
G01X241086Y130500D02*
G03X239837Y133516I-4266J0D01*
G01X239935Y130500D02*
G03X239023Y132702I-3114J0D01*
G01X241086Y128540D02*
Y130500D01*
G01X239935Y129270D02*
Y130500D01*
G01X239936Y128472D02*
Y128965D01*
G01X242700Y114800D02*
X241086Y128540D01*
G01X241570Y114557D02*
X239936Y128472D01*
G01X225341Y130500D02*
Y128540D01*
G01X224191Y128965D02*
Y128331D01*
G01X224190Y130500D02*
Y129270D01*
G01X224092Y133516D02*
G02X225341Y130500I-3017J-3016D01*
G01X223278Y132702D02*
G02X224190Y130500I-2202J-2202D01*
G01X223564Y134044D02*
X224092Y133516D01*
G01X222750Y133230D02*
X223278Y132702D01*
G01X221451Y139145D02*
G03X223564Y134044I7214J0D01*
G01X220301Y139144D02*
G03X222750Y133230I8365J0D01*
G01X221451Y147640D02*
Y139145D01*
G01X220301Y147640D02*
Y139144D01*
G01X223067Y151543D02*
G03X221451Y147640I3903J-3902D01*
G01X222254Y152357D02*
G03X220301Y147640I4716J-4716D01*
G01X223395Y151870D02*
X223067Y151543D01*
G01X222419Y152523D02*
X222254Y152357D01*
G01X222582Y152685D02*
X222419Y152523D01*
G01X225332Y156722D02*
G02X223395Y151870I-6622J-169D01*
G01X224184Y156554D02*
G02X222582Y152685I-5473J0D01*
G01X224906Y158216D02*
X225332Y156722D01*
G01X223800Y157900D02*
X224184Y156554D01*
G01X224845Y158430D02*
X224905Y158220D01*
G01X223800Y157900D02*
X224184Y156554D01*
G01X223745Y158091D02*
X223797Y157908D01*
G01X219300Y175200D02*
X224845Y158430D01*
G01X218241Y174738D02*
X223745Y158091D01*
G01X209479Y193019D02*
X219300Y175200D01*
G01X208496Y192417D02*
X218241Y174738D01*
G01X208435Y158172D02*
X200788Y183647D01*
G01X201846Y184125D02*
X209585Y158341D01*
G01X208435Y156553D02*
Y158172D01*
G01X209585Y158341D02*
Y156554D01*
G01X206832Y152685D02*
G03X208434Y156554I-3871J3869D01*
G01X209585D02*
G02X207645Y151870I-6624J0D01*
G01X206669Y152523D02*
X206832Y152685D01*
G01X207645Y151870D02*
X207317Y151543D01*
G01X206504Y152357D02*
X206669Y152523D01*
G01X207645Y151870D02*
X207317Y151543D01*
G01X204551Y147640D02*
G02X206504Y152357I6669J1D01*
G01X207317Y151543D02*
G03X205701Y147640I3903J-3902D01*
G01X204551Y139144D02*
Y147640D01*
G01X205701D02*
Y139145D01*
G01X207000Y133230D02*
G02X204551Y139144I5916J5914D01*
G01X205701Y139145D02*
G03X207814Y134044I7214J0D01*
G01X207528Y132702D02*
X207000Y133230D01*
G01X207814Y134044D02*
X208342Y133516D01*
G01X208441Y130500D02*
G03X207528Y132702I-3115J-1D01*
G01X208342Y133516D02*
G02X209591Y130500I-3017J-3016D01*
G01X208918Y126536D02*
X208441Y130429D01*
G01X209591Y130500D02*
X210068Y126607D01*
G01X208918Y126015D02*
Y126536D01*
G01X210068Y126607D02*
Y126234D01*
G01Y126607D02*
Y126234D01*
G01X208918Y126015D02*
Y126536D01*
G01X209591Y130500D02*
X210068Y126607D01*
G01X208918Y126536D02*
X208441Y130429D01*
G01X208342Y133516D02*
G02X209591Y130500I-3017J-3016D01*
G01X208441D02*
G03X207528Y132702I-3115J-1D01*
G01X207814Y134044D02*
X208342Y133516D01*
G01X207528Y132702D02*
X207000Y133230D01*
G01X205701Y139145D02*
G03X207814Y134044I7214J0D01*
G01X207000Y133230D02*
G02X204551Y139144I5916J5914D01*
G01X205701Y147640D02*
Y139145D01*
G01X204551Y139144D02*
Y147640D01*
G01X207317Y151543D02*
G03X205701Y147640I3903J-3902D01*
G01X204551D02*
G02X206504Y152357I6669J1D01*
G01X207645Y151870D02*
X207317Y151543D01*
G01X206669Y152523D02*
X206832Y152685D01*
G01X206504Y152357D02*
X206669Y152523D01*
G01X209585Y156554D02*
G02X207645Y151870I-6624J0D01*
G01X206832Y152685D02*
G03X208434Y156554I-3871J3869D01*
G01X209585Y158341D02*
Y156554D01*
G01X208435Y156553D02*
Y158172D01*
G01X201846Y184125D02*
X209585Y158341D01*
G01X208435Y158172D02*
X200788Y183647D01*
G01X266299Y231307D02*
X266298D01*
G01X267260Y232113D02*
X266813Y232337D01*
G01X266567Y231173D02*
X266299Y231307D01*
G01X266813Y232337D02*
X266812D01*
G01X267260Y232113D02*
X266813Y232337D01*
G01X267619Y228468D02*
G03X266567Y231173I-4004J0D01*
G01X266871Y216745D02*
G03X267245Y218303I-2706J1473D01*
G01X265110Y214514D02*
G03X266871Y216745I-5636J6259D01*
G01X265880Y213659D02*
G03X267881Y216195I-6407J7112D01*
G01X263779Y210990D02*
G02X265110Y214514I4080J472D01*
G01X264929Y211062D02*
G02X265880Y213659I2930J400D01*
G01X263779Y208142D02*
Y210990D01*
G01X264929Y208397D02*
Y211062D01*
G01X264511Y206572D02*
X263779Y208142D01*
G01X286900Y161300D02*
X264929Y208397D01*
G01X266320Y202694D02*
X265686Y204053D01*
G01X286900Y161300D02*
X264929Y208397D01*
G01X286900Y161300D02*
X264929Y208397D01*
G01X266813Y232337D02*
X266812D01*
G01X266567Y231173D02*
X266299Y231307D01*
G01X267260Y232113D02*
X266813Y232337D01*
G01X266299Y231307D02*
X266298D01*
G01X266567Y231173D02*
X266299Y231307D01*
G01X267619Y228468D02*
G03X266567Y231173I-4004J0D01*
G01X266871Y216745D02*
G03X267245Y218303I-2706J1473D01*
G01X265880Y213659D02*
G03X267881Y216195I-6407J7112D01*
G01X265110Y214514D02*
G03X266871Y216745I-5636J6259D01*
G01X264929Y211062D02*
G02X265880Y213659I2930J400D01*
G01X263779Y210990D02*
G02X265110Y214514I4080J472D01*
G01X264929Y208397D02*
Y211062D01*
G01X263779Y208142D02*
Y210990D01*
G01X286900Y161300D02*
X264929Y208397D01*
G01X264511Y206572D02*
X263779Y208142D01*
G01X266320Y202694D02*
X265686Y204053D01*
G01X257523Y214623D02*
X257524D01*
G01X257590Y213369D02*
X258037Y213593D01*
G01X257142Y214432D02*
X257523Y214623D01*
G01X258037Y213593D02*
X258038D01*
G01X257590Y213369D02*
X258037Y213593D01*
G01X256921Y214321D02*
X257142Y214432D01*
G01X257590Y213369D02*
X258037Y213593D01*
G01X255510Y211125D02*
G02X256921Y214321I4325J0D01*
G01X256660Y211124D02*
G02X257590Y213369I3175J0D01*
G01X255510Y207845D02*
Y211125D01*
G01X256660Y207845D02*
Y211124D01*
G01X256471Y205522D02*
G02X255510Y207845I2324J2322D01*
G01X257285Y206336D02*
G02X256660Y207845I1509J1509D01*
G01X257192Y204801D02*
X256471Y205522D01*
G01X258099D02*
X257285Y206336D01*
G01X269672Y184781D02*
X257192Y204801D01*
G01X258893Y204249D02*
X258099Y205522D01*
G01X261157Y200617D02*
X260363Y201890D01*
G01X263421Y196985D02*
X262627Y198258D01*
G01X271141Y184600D02*
X264891Y194626D01*
G01X271141Y184600D02*
X264891Y194626D01*
G01X271141Y184600D02*
X264891Y194626D01*
G01X258037Y213593D02*
X258038D01*
G01X257142Y214432D02*
X257523Y214623D01*
G01X257590Y213369D02*
X258037Y213593D01*
G01X257523Y214623D02*
X257524D01*
G01X257142Y214432D02*
X257523Y214623D01*
G01X256921Y214321D02*
X257142Y214432D01*
G01X256660Y211124D02*
G02X257590Y213369I3175J0D01*
G01X255510Y211125D02*
G02X256921Y214321I4325J0D01*
G01X256660Y207845D02*
Y211124D01*
G01X255510Y207845D02*
Y211125D01*
G01X257285Y206336D02*
G02X256660Y207845I1509J1509D01*
G01X256471Y205522D02*
G02X255510Y207845I2324J2322D01*
G01X258099Y205522D02*
X257285Y206336D01*
G01X257192Y204801D02*
X256471Y205522D01*
G01X258893Y204249D02*
X258099Y205522D01*
G01X269672Y184781D02*
X257192Y204801D01*
G01X261157Y200617D02*
X260363Y201890D01*
G01X269672Y184781D02*
X257192Y204801D01*
G01X263421Y196985D02*
X262627Y198258D01*
G01X269672Y184781D02*
X257192Y204801D01*
G01X271141Y184600D02*
X264891Y194626D01*
G01X269672Y184781D02*
X257192Y204801D01*
G01X249643Y197849D02*
X257947Y188838D01*
G01X241858Y207995D02*
X258898Y189505D01*
G01X247759Y199893D02*
X249643Y197849D01*
G01X241858Y207995D02*
X258898Y189505D01*
G01X246743Y200996D02*
X247759Y199893D01*
G01X241858Y207995D02*
X258898Y189505D01*
G01X243842Y204144D02*
X244859Y203041D01*
G01X241858Y207995D02*
X258898Y189505D01*
G01X240942Y207291D02*
X241959Y206188D01*
G01X241858Y207995D02*
X258898Y189505D01*
G01X240660Y207735D02*
X240942Y207291D01*
G01X241653Y208319D02*
X241858Y207995D01*
G01X240463Y208186D02*
X240647Y207738D01*
G01X241634Y208365D02*
X241653Y208319D01*
G01X241549Y208569D02*
X241634Y208364D01*
G01X240136Y209290D02*
X240463Y208186D01*
G01X241286Y209457D02*
X241549Y208569D01*
G01X240136Y211676D02*
Y209290D01*
G01X241286Y211675D02*
Y209457D01*
G01X240982Y213720D02*
G03X240136Y211676I2046J-2044D01*
G01X241796Y212906D02*
G03X241286Y211675I1231J-1231D01*
G01X243086Y215825D02*
X240982Y213720D01*
G01X243900Y215011D02*
X241796Y212906D01*
G01X243995Y218019D02*
G02X243086Y215825I-3096J-3D01*
G01X245145Y218019D02*
G02X243900Y215011I-4247J-4D01*
G01X243995Y228467D02*
Y218019D01*
G01X245145Y228468D02*
Y218019D01*
G01X242942Y231173D02*
G02X243995Y228467I-2952J-2707D01*
G01X243635Y232113D02*
G02X245145Y228468I-3645J-3645D01*
G01X242674Y231307D02*
X242942Y231173D01*
G01X243188Y232337D02*
X243635Y232113D01*
G01X243187Y232337D02*
X243188D01*
G01X242673Y231307D02*
X242674D01*
G01X243188Y232337D02*
X243635Y232113D01*
G01X241858Y207995D02*
X258898Y189505D01*
G01X249643Y197849D02*
X257947Y188838D01*
G01X247759Y199893D02*
X249643Y197849D01*
G01X246743Y200996D02*
X247759Y199893D01*
G01X243842Y204144D02*
X244859Y203041D01*
G01X240942Y207291D02*
X241959Y206188D01*
G01X241653Y208319D02*
X241858Y207995D01*
G01X240660Y207735D02*
X240942Y207291D01*
G01X241634Y208365D02*
X241653Y208319D01*
G01X240463Y208186D02*
X240647Y207738D01*
G01X241549Y208569D02*
X241634Y208364D01*
G01X240463Y208186D02*
X240647Y207738D01*
G01X241286Y209457D02*
X241549Y208569D01*
G01X240136Y209290D02*
X240463Y208186D01*
G01X241286Y211675D02*
Y209457D01*
G01X240136Y211676D02*
Y209290D01*
G01X241796Y212906D02*
G03X241286Y211675I1231J-1231D01*
G01X240982Y213720D02*
G03X240136Y211676I2046J-2044D01*
G01X243900Y215011D02*
X241796Y212906D01*
G01X243086Y215825D02*
X240982Y213720D01*
G01X245145Y218019D02*
G02X243900Y215011I-4247J-4D01*
G01X243995Y218019D02*
G02X243086Y215825I-3096J-3D01*
G01X245145Y228468D02*
Y218019D01*
G01X243995Y228467D02*
Y218019D01*
G01X243635Y232113D02*
G02X245145Y228468I-3645J-3645D01*
G01X242942Y231173D02*
G02X243995Y228467I-2952J-2707D01*
G01X243188Y232337D02*
X243635Y232113D01*
G01X242674Y231307D02*
X242942Y231173D01*
G01X242673Y231307D02*
X242674D01*
G01X243187Y232337D02*
X243188D01*
G01X242674Y231307D02*
X242942Y231173D01*
G01X233898Y214623D02*
X233899D01*
G01X233965Y213369D02*
X234412Y213593D01*
G01X233517Y214432D02*
X233898Y214623D01*
G01X234412Y213593D02*
X234413D01*
G01X233965Y213369D02*
X234412Y213593D01*
G01X233296Y214321D02*
X233517Y214432D01*
G01X233965Y213369D02*
X234412Y213593D01*
G01X231885Y211064D02*
G02X233296Y214321I4325J60D01*
G01X233035Y211124D02*
G02X233965Y213369I3175J0D01*
G01X232182Y208012D02*
X231885Y211064D01*
G01X233300Y208400D02*
X233035Y211124D01*
G01X234111Y207138D02*
X233300Y208400D01*
G01X236426Y203538D02*
X235614Y204800D01*
G01X238740Y199938D02*
X237929Y201199D01*
G01X241819Y195149D02*
X240243Y197599D01*
G01X234412Y213593D02*
X234413D01*
G01X233517Y214432D02*
X233898Y214623D01*
G01X233965Y213369D02*
X234412Y213593D01*
G01X233898Y214623D02*
X233899D01*
G01X233517Y214432D02*
X233898Y214623D01*
G01X233296Y214321D02*
X233517Y214432D01*
G01X233035Y211124D02*
G02X233965Y213369I3175J0D01*
G01X231885Y211064D02*
G02X233296Y214321I4325J60D01*
G01X233300Y208400D02*
X233035Y211124D01*
G01X232182Y208012D02*
X231885Y211064D01*
G01X234111Y207138D02*
X233300Y208400D01*
G01X236426Y203538D02*
X235614Y204800D01*
G01X238740Y199938D02*
X237929Y201199D01*
G01X241819Y195149D02*
X240243Y197599D01*
G01X233455Y193762D02*
X237909Y186448D01*
G01X234437Y194361D02*
X238962Y186931D01*
G01X228930Y201170D02*
X233455Y193762D01*
G01X229912Y201770D02*
X234437Y194361D01*
G01X226700Y204823D02*
X227481Y203543D01*
G01X225619Y208800D02*
X229912Y201770D01*
G01X224469Y208476D02*
X225251Y207196D01*
G01X225619Y208800D02*
X229912Y201770D01*
G01X224469Y211875D02*
Y208476D01*
G01X225619Y211874D02*
Y208800D01*
G01X225524Y214425D02*
G03X224469Y211875I2553J-2550D01*
G01X226338Y213611D02*
G03X225619Y211874I1739J-1737D01*
G01X227038Y215938D02*
X225524Y214425D01*
G01X227851Y215124D02*
X226338Y213611D01*
G01X227124Y216052D02*
G02X227038Y215938I-438J241D01*
G01X228134Y215502D02*
G02X227851Y215124I-1449J790D01*
G01X227501Y216745D02*
X227124Y216052D01*
G01X228511Y216195D02*
X228134Y215502D01*
G01X227875Y218291D02*
G02X227501Y216745I-3080J-73D01*
G01X229025Y218318D02*
G02X228511Y216195I-4230J-100D01*
G01X227875Y222837D02*
Y218291D01*
G01X229025Y222761D02*
Y218318D01*
G01X228249Y228468D02*
G02X227884Y222912I-42463J0D01*
G01X229400Y228468D02*
G02X229025Y222761I-43614J0D01*
G01X227197Y231173D02*
G02X228249Y228468I-2952J-2705D01*
G01X227890Y232113D02*
G02X229400Y228468I-3645J-3645D01*
G01X226929Y231307D02*
X227197Y231173D01*
G01X227443Y232337D02*
X227890Y232113D01*
G01X227442Y232337D02*
X227443D01*
G01X226928Y231307D02*
X226929D01*
G01X227443Y232337D02*
X227890Y232113D01*
G01X211179Y231307D02*
X211178D01*
G01X212140Y232113D02*
X211693Y232337D01*
G01X211447Y231173D02*
X211179Y231307D01*
G01X211693Y232337D02*
X211692D01*
G01X212140Y232113D02*
X211693Y232337D01*
G01X212500Y228467D02*
G03X211447Y231173I-4005J-1D01*
G01X213650Y228468D02*
G03X212140Y232113I-5155J0D01*
G01X212500Y218019D02*
Y228467D01*
G01X213650Y218019D02*
Y228468D01*
G01X211591Y215825D02*
G03X212500Y218019I-2187J2191D01*
G01X212405Y215011D02*
G03X213650Y218019I-3002J3004D01*
G01X209487Y213720D02*
X211591Y215825D01*
G01X210301Y212906D02*
X212405Y215011D01*
G01X208641Y211676D02*
G02X209487Y213720I2892J0D01*
G01X209791Y211675D02*
G02X210301Y212906I1741J0D01*
G01X208641Y209196D02*
Y211676D01*
G01X209791Y209457D02*
Y211675D01*
G01X209287Y207842D02*
X208641Y209196D01*
G01X220959Y186066D02*
X209791Y209457D01*
G01X211131Y203980D02*
X210485Y205334D01*
G01X220959Y186066D02*
X209791Y209457D01*
G01X219963Y185482D02*
X212329Y201471D01*
G01X220959Y186066D02*
X209791Y209457D01*
G01X221416Y183424D02*
X219969Y185472D01*
G01X224413Y181175D02*
X220959Y186066D01*
G01X223416Y180592D02*
X221416Y183424D01*
G01X224413Y181175D02*
X220959Y186066D01*
G01X190147Y232114D02*
X190594Y232337D01*
G01X191110Y231309D02*
X190662Y231085D01*
G01X191111Y231309D02*
X191110D01*
G01X189995Y232038D02*
X190147Y232114D01*
G01X191110Y231309D02*
X190662Y231085D01*
G01X189848Y231898D02*
G02X189995Y232038I2742J-2732D01*
G01X190662Y231085D02*
G03X189865Y229161I1924J-1924D01*
G01X188715Y229162D02*
G02X189848Y231898I3871J0D01*
G01X190662Y231085D02*
G03X189865Y229161I1924J-1924D01*
G01X188715Y225917D02*
Y229162D01*
G01X189865Y229161D02*
Y226032D01*
G01X189465Y222189D02*
X188715Y225917D01*
G01X189865Y226032D02*
X190629Y222237D01*
G01X189287Y220671D02*
X189465Y222189D01*
G01X190629Y222237D02*
X190429Y220534D01*
G01X189078Y218976D02*
X189287Y220671D01*
G01X190429Y220534D02*
X190214Y218786D01*
G01X190413Y214434D02*
G02X189078Y218975I3495J3494D01*
G01X190203Y218734D02*
G03X191227Y215248I3705J-805D01*
G01X191269Y213578D02*
X190413Y214434D01*
G01X191227Y215248D02*
X192083Y214392D01*
G01X192858Y209742D02*
G03X191269Y213578I-5425J0D01*
G01X192083Y214392D02*
G02X194009Y209742I-4650J-4650D01*
G01X193172Y204998D02*
X192860Y209650D01*
G01X194008Y209727D02*
X194310Y205220D01*
G01X193600Y203700D02*
X193172Y204998D01*
G01X194310Y205220D02*
X194692Y204061D01*
G01X199380Y196899D02*
X200202Y195644D01*
G01X197036Y200480D02*
X197858Y199225D01*
G01X194692Y204061D02*
X195513Y202806D01*
G01X234437Y194361D02*
X238962Y186931D01*
G01X233455Y193762D02*
X237909Y186448D01*
G01X229912Y201770D02*
X234437Y194361D01*
G01X228930Y201170D02*
X233455Y193762D01*
G01X225619Y208800D02*
X229912Y201770D01*
G01X226700Y204823D02*
X227481Y203543D01*
G01X224469Y208476D02*
X225251Y207196D01*
G01X225619Y211874D02*
Y208800D01*
G01X224469Y211875D02*
Y208476D01*
G01X226338Y213611D02*
G03X225619Y211874I1739J-1737D01*
G01X225524Y214425D02*
G03X224469Y211875I2553J-2550D01*
G01X227851Y215124D02*
X226338Y213611D01*
G01X227038Y215938D02*
X225524Y214425D01*
G01X228134Y215502D02*
G02X227851Y215124I-1449J790D01*
G01X227124Y216052D02*
G02X227038Y215938I-438J241D01*
G01X228511Y216195D02*
X228134Y215502D01*
G01X227501Y216745D02*
X227124Y216052D01*
G01X229025Y218318D02*
G02X228511Y216195I-4230J-100D01*
G01X227875Y218291D02*
G02X227501Y216745I-3080J-73D01*
G01X229025Y222761D02*
Y218318D01*
G01X227875Y222837D02*
Y218291D01*
G01X229400Y228468D02*
G02X229025Y222761I-43614J0D01*
G01X228249Y228468D02*
G02X227884Y222912I-42463J0D01*
G01X227890Y232113D02*
G02X229400Y228468I-3645J-3645D01*
G01X227197Y231173D02*
G02X228249Y228468I-2952J-2705D01*
G01X227443Y232337D02*
X227890Y232113D01*
G01X226929Y231307D02*
X227197Y231173D01*
G01X226928Y231307D02*
X226929D01*
G01X227442Y232337D02*
X227443D01*
G01X226929Y231307D02*
X227197Y231173D01*
G01X211693Y232337D02*
X211692D01*
G01X211447Y231173D02*
X211179Y231307D01*
G01X212140Y232113D02*
X211693Y232337D01*
G01X211179Y231307D02*
X211178D01*
G01X211447Y231173D02*
X211179Y231307D01*
G01X213650Y228468D02*
G03X212140Y232113I-5155J0D01*
G01X212500Y228467D02*
G03X211447Y231173I-4005J-1D01*
G01X213650Y218019D02*
Y228468D01*
G01X212500Y218019D02*
Y228467D01*
G01X212405Y215011D02*
G03X213650Y218019I-3002J3004D01*
G01X211591Y215825D02*
G03X212500Y218019I-2187J2191D01*
G01X210301Y212906D02*
X212405Y215011D01*
G01X209487Y213720D02*
X211591Y215825D01*
G01X209791Y211675D02*
G02X210301Y212906I1741J0D01*
G01X208641Y211676D02*
G02X209487Y213720I2892J0D01*
G01X209791Y209457D02*
Y211675D01*
G01X208641Y209196D02*
Y211676D01*
G01X220959Y186066D02*
X209791Y209457D01*
G01X209287Y207842D02*
X208641Y209196D01*
G01X211131Y203980D02*
X210485Y205334D01*
G01X219963Y185482D02*
X212329Y201471D01*
G01X224413Y181175D02*
X220959Y186066D01*
G01X221416Y183424D02*
X219969Y185472D01*
G01X223416Y180592D02*
X221416Y183424D01*
G01X199380Y196899D02*
X200202Y195644D01*
G01X197036Y200480D02*
X197858Y199225D01*
G01X194692Y204061D02*
X195513Y202806D01*
G01X194310Y205220D02*
X194692Y204061D01*
G01X193600Y203700D02*
X193172Y204998D01*
G01X194008Y209727D02*
X194310Y205220D01*
G01X193172Y204998D02*
X192860Y209650D01*
G01X192083Y214392D02*
G02X194009Y209742I-4650J-4650D01*
G01X192858D02*
G03X191269Y213578I-5425J0D01*
G01X191227Y215248D02*
X192083Y214392D01*
G01X191269Y213578D02*
X190413Y214434D01*
G01X190203Y218734D02*
G03X191227Y215248I3705J-805D01*
G01X190413Y214434D02*
G02X189078Y218975I3495J3494D01*
G01X190429Y220534D02*
X190214Y218786D01*
G01X189078Y218976D02*
X189287Y220671D01*
G01X190629Y222237D02*
X190429Y220534D01*
G01X189287Y220671D02*
X189465Y222189D01*
G01X189865Y226032D02*
X190629Y222237D01*
G01X189465Y222189D02*
X188715Y225917D01*
G01X189865Y229161D02*
Y226032D01*
G01X188715Y225917D02*
Y229162D01*
G01X190662Y231085D02*
G03X189865Y229161I1924J-1924D01*
G01X189848Y231898D02*
G02X189995Y232038I2742J-2732D01*
G01X188715Y229162D02*
G02X189848Y231898I3871J0D01*
G01X191110Y231309D02*
X190662Y231085D01*
G01X190147Y232114D02*
X190594Y232337D01*
G01X189995Y232038D02*
X190147Y232114D01*
G01X191111Y231309D02*
X191110D01*
G01X190147Y232114D02*
X190594Y232337D01*
G01X218153Y214623D02*
X218154D01*
G01X218220Y213369D02*
X218667Y213593D01*
G01X217772Y214432D02*
X218153Y214623D01*
G01X218667Y213593D02*
X218668D01*
G01X218220Y213369D02*
X218667Y213593D01*
G01X217551Y214321D02*
X217772Y214432D01*
G01X218220Y213369D02*
X218667Y213593D01*
G01X216140Y211124D02*
G02X217551Y214321I4325J1D01*
G01X217290Y211124D02*
G02X218220Y213369I3175J0D01*
G01X216141Y211011D02*
G02X216140Y211124I4324J95D01*
G01X217290D02*
G02X218220Y213369I3175J0D01*
G01X216193Y210510D02*
X216144Y211009D01*
G01X217338Y210623D02*
X217289Y211122D01*
G01X216202Y210421D02*
X216193Y210510D01*
G01X217338Y210623D02*
X217289Y211122D01*
G01X220476Y193968D02*
X216202Y210421D01*
G01X218272Y207028D02*
X217338Y210623D01*
G01X219348Y202885D02*
X218971Y204337D01*
G01X220424Y198743D02*
X220047Y200194D01*
G01X221500Y194600D02*
X221123Y196052D01*
G01X228844Y186632D02*
X220475Y193968D01*
G01X229600Y187500D02*
X221500Y194600D01*
G01X230142Y187031D02*
X229600Y187500D01*
G01X229223Y186305D02*
X228844Y186632D01*
G01X229600Y187500D02*
X221500Y194600D01*
G01X230142Y187031D02*
X229600Y187500D01*
G01X201200Y202900D02*
X208496Y192417D01*
G01X207034Y196531D02*
X207891Y195300D01*
G01X204589Y200044D02*
X205446Y198813D01*
G01X202144Y203557D02*
X203001Y202326D01*
G01X201069Y203087D02*
X201200Y202900D01*
G01X202144Y203557D02*
X203001Y202326D01*
G01X200390Y206174D02*
X201069Y203087D01*
G01X201540Y206300D02*
X202144Y203557D01*
G01X200390Y211123D02*
Y206174D01*
G01X201540Y211124D02*
Y206300D01*
G01X200390Y211125D02*
G03Y211123I4326J-1D01*
G01X202469Y213369D02*
G03X201540Y211124I2246J-2244D01*
G01X201801Y214321D02*
G03X200390Y211125I2914J-3196D01*
G01X202469Y213369D02*
G03X201540Y211124I2246J-2244D01*
G01X202022Y214432D02*
X201801Y214321D01*
G01X202507Y213388D02*
X202469Y213369D01*
G01X202508Y213388D02*
X202507D01*
G01X202917Y213593D02*
X202508Y213388D01*
G01X202403Y214623D02*
X202022Y214432D01*
G01X202507Y213388D02*
X202469Y213369D01*
G01X202508Y213388D02*
X202507D01*
G01X202917Y213593D02*
X202508Y213388D01*
G01X202918Y213593D02*
X202917D01*
G01X202404Y214623D02*
X202403D01*
G01X202917Y213593D02*
X202508Y213388D01*
G01X218667Y213593D02*
X218668D01*
G01X217772Y214432D02*
X218153Y214623D01*
G01X218220Y213369D02*
X218667Y213593D01*
G01X218153Y214623D02*
X218154D01*
G01X217772Y214432D02*
X218153Y214623D01*
G01X217551Y214321D02*
X217772Y214432D01*
G01X217290Y211124D02*
G02X218220Y213369I3175J0D01*
G01X216140Y211124D02*
G02X217551Y214321I4325J1D01*
G01X216141Y211011D02*
G02X216140Y211124I4324J95D01*
G01X217338Y210623D02*
X217289Y211122D01*
G01X216193Y210510D02*
X216144Y211009D01*
G01X216202Y210421D02*
X216193Y210510D01*
G01X218272Y207028D02*
X217338Y210623D01*
G01X220476Y193968D02*
X216202Y210421D01*
G01X219348Y202885D02*
X218971Y204337D01*
G01X220476Y193968D02*
X216202Y210421D01*
G01X220424Y198743D02*
X220047Y200194D01*
G01X220476Y193968D02*
X216202Y210421D01*
G01X221500Y194600D02*
X221123Y196052D01*
G01X220476Y193968D02*
X216202Y210421D01*
G01X229600Y187500D02*
X221500Y194600D01*
G01X228844Y186632D02*
X220475Y193968D01*
G01X229223Y186305D02*
X228844Y186632D01*
G01X230142Y187031D02*
X229600Y187500D01*
G01X228844Y186632D02*
X220475Y193968D01*
G01X229223Y186305D02*
X228844Y186632D01*
G01X207034Y196531D02*
X207891Y195300D01*
G01X201200Y202900D02*
X208496Y192417D01*
G01X204589Y200044D02*
X205446Y198813D01*
G01X201200Y202900D02*
X208496Y192417D01*
G01X202144Y203557D02*
X203001Y202326D01*
G01X201200Y202900D02*
X208496Y192417D01*
G01X201069Y203087D02*
X201200Y202900D01*
G01X201540Y206300D02*
X202144Y203557D01*
G01X200390Y206174D02*
X201069Y203087D01*
G01X201540Y211124D02*
Y206300D01*
G01X200390Y211123D02*
Y206174D01*
G01X202469Y213369D02*
G03X201540Y211124I2246J-2244D01*
G01X200390Y211125D02*
G03Y211123I4326J-1D01*
G01X201801Y214321D02*
G03X200390Y211125I2914J-3196D01*
G01X202507Y213388D02*
X202469Y213369D01*
G01X202022Y214432D02*
X201801Y214321D01*
G01X202403Y214623D02*
X202022Y214432D01*
G01X202508Y213388D02*
X202507D01*
G01X202022Y214432D02*
X201801Y214321D01*
G01X202403Y214623D02*
X202022Y214432D01*
G01X202917Y213593D02*
X202508Y213388D01*
G01X202022Y214432D02*
X201801Y214321D01*
G01X202403Y214623D02*
X202022Y214432D01*
G01X202404Y214623D02*
X202403D01*
G01X202918Y213593D02*
X202917D01*
G01X202403Y214623D02*
X202022Y214432D01*
G01X188693Y203016D02*
X187898Y204289D01*
G01X200357Y184338D02*
X190165Y200658D01*
G01X200788Y183647D02*
X200357Y184338D01*
G01X201764Y184257D02*
X201846Y184125D01*
G01X201764Y184257D02*
X201846Y184125D01*
G01X200788Y183647D02*
X200357Y184338D01*
G01X188693Y203016D02*
X187898Y204289D01*
G01X200357Y184338D02*
X190165Y200658D01*
G01X200788Y183647D02*
X200357Y184338D01*
G01X209529Y533700D02*
G03X210316Y534488I0J787D01*
G01Y563228D02*
Y534488D01*
G01X212284Y565196D02*
X210316Y563228D01*
G01X426536Y565196D02*
X212284D01*
G01X357738Y8176D02*
X339213Y21148D01*
G01X358488Y9055D02*
X340039Y21974D01*
G01X330291Y13509D02*
X361005Y-7999D01*
G01X361831Y-7173D02*
X331117Y14335D01*
G01X315044Y35271D02*
X330291Y13509D01*
G01X331117Y14335D02*
X316133Y35722D01*
G01X358488Y9055D02*
X340039Y21974D01*
G01X357738Y8176D02*
X339213Y21148D01*
G01X331117Y14335D02*
X316133Y35722D01*
G01X315044Y35271D02*
X330291Y13509D01*
G01X361831Y-7173D02*
X331117Y14335D01*
G01X330291Y13509D02*
X361005Y-7999D01*
G01X333280Y16494D02*
X318839Y37118D01*
G01X319928Y37569D02*
X334106Y17320D01*
G01X364216Y-5168D02*
X333280Y16494D01*
G01X334106Y17320D02*
X365042Y-4342D01*
G01X327908Y10171D02*
X356348Y-9744D01*
G01X357174Y-8918D02*
X328734Y10997D01*
G01X306164Y41219D02*
X327908Y10171D01*
G01X328734Y10997D02*
X307253Y41670D01*
G01X334106Y17320D02*
X365042Y-4342D01*
G01X364216Y-5168D02*
X333280Y16494D01*
G01X319928Y37569D02*
X334106Y17320D01*
G01X333280Y16494D02*
X318839Y37118D01*
G01X328734Y10997D02*
X307253Y41670D01*
G01X306164Y41219D02*
X327908Y10171D01*
G01X357174Y-8918D02*
X328734Y10997D01*
G01X327908Y10171D02*
X356348Y-9744D01*
G01X324945Y7618D02*
X299567Y43857D01*
G01X325771Y8444D02*
X300656Y44308D01*
G01X352248Y-11499D02*
X324945Y7618D01*
G01X352908Y-10557D02*
X325771Y8444D01*
G01D02*
X300656Y44308D01*
G01X324945Y7618D02*
X299567Y43857D01*
G01X352908Y-10557D02*
X325771Y8444D01*
G01X352248Y-11499D02*
X324945Y7618D01*
G01X322326Y4972D02*
X293921Y45548D01*
G01X323152Y5798D02*
X295010Y45999D01*
G01X347606Y-12728D02*
X322326Y4972D01*
G01X348432Y-11902D02*
X323152Y5798D01*
G01D02*
X295010Y45999D01*
G01X322326Y4972D02*
X293921Y45548D01*
G01X348432Y-11902D02*
X323152Y5798D01*
G01X347606Y-12728D02*
X322326Y4972D01*
G01X345608Y-16547D02*
X357205Y-33105D01*
G01X346434Y-15721D02*
X358294Y-32654D01*
G01X320309Y1170D02*
X345608Y-16547D01*
G01X321135Y1996D02*
X346434Y-15721D01*
G01X284980Y51626D02*
X320309Y1170D01*
G01X286069Y52077D02*
X321135Y1996D01*
G01X346434Y-15721D02*
X358294Y-32654D01*
G01X345608Y-16547D02*
X357205Y-33105D01*
G01X321135Y1996D02*
X346434Y-15721D01*
G01X320309Y1170D02*
X345608Y-16547D01*
G01X286069Y52077D02*
X321135Y1996D01*
G01X284980Y51626D02*
X320309Y1170D01*
G01X317218Y-1726D02*
X276176Y56888D01*
G01X318103Y-983D02*
X277265Y57339D01*
G01X317649Y-2157D02*
X317218Y-1726D01*
G01X318463Y-1343D02*
X318103Y-983D01*
G01X317651Y-2169D02*
X317649Y-2167D01*
G01X318463Y-1343D02*
X318103Y-983D01*
G01X342432Y-19522D02*
X317651Y-2169D01*
G01X318477Y-1343D02*
X318463D01*
G01X343258Y-18696D02*
X318477Y-1343D01*
G01X352182Y-33445D02*
X342432Y-19522D01*
G01X353332Y-33082D02*
X343258Y-18696D01*
G01X318103Y-983D02*
X277265Y57339D01*
G01X317218Y-1726D02*
X276176Y56888D01*
G01X318463Y-1343D02*
X318103Y-983D01*
G01X317649Y-2157D02*
X317218Y-1726D01*
G01X317651Y-2169D02*
X317649Y-2167D01*
G01X318477Y-1343D02*
X318463D01*
G01X342432Y-19522D02*
X317651Y-2169D01*
G01X343258Y-18696D02*
X318477Y-1343D01*
G01X342432Y-19522D02*
X317651Y-2169D01*
G01X353332Y-33082D02*
X343258Y-18696D01*
G01X352182Y-33445D02*
X342432Y-19522D01*
G01X346856Y-33137D02*
X347132Y-34703D01*
G01X338754Y-21566D02*
X346856Y-33137D01*
G01X339580Y-20740D02*
X347945Y-32686D01*
G01X326713Y-13135D02*
X338754Y-21566D01*
G01X315165Y-3645D02*
X339580Y-20740D01*
G01X314339Y-4471D02*
X326713Y-13135D01*
G01X315165Y-3645D02*
X339580Y-20740D01*
G01X268078Y63604D02*
X315165Y-3645D01*
G01X331889Y-26448D02*
X308457Y-10040D01*
G01X332715Y-25622D02*
X309283Y-9214D01*
G01X336802Y-33463D02*
X331889Y-26448D01*
G01X337891Y-33013D02*
X332715Y-25622D01*
G01X336932Y-34204D02*
X336802Y-33464D01*
G01X338082Y-34103D02*
X337891Y-33013D01*
G01X336932Y-34704D02*
Y-34204D01*
G01X338082Y-34668D02*
Y-34103D01*
G01X336932Y-34711D02*
G02Y-34704I3118J3D01*
G01X339442Y-36479D02*
G02X338082Y-34668I607J1872D01*
G01X302584Y-15130D02*
G02X302179Y-14725I947J1352D01*
G01X303121Y-14065D02*
G03X303244Y-14188I410J287D01*
G01X323845Y-30030D02*
X302584Y-15130D01*
G01X303244Y-14188D02*
X324595Y-29150D01*
G01X325275Y-31502D02*
X323845Y-30030D01*
G01X326100Y-30700D02*
X326192Y-30795D01*
G01X324595Y-29150D02*
X326100Y-30700D01*
G01X326710Y-33879D02*
X325275Y-31502D01*
G01X326192Y-30795D02*
X327852Y-33545D01*
G01X326732Y-34711D02*
X326710Y-33879D01*
G01X327852Y-33545D02*
X327882Y-34673D01*
G01X346856Y-33137D02*
X347132Y-34703D01*
G01X339580Y-20740D02*
X347945Y-32686D01*
G01X338754Y-21566D02*
X346856Y-33137D01*
G01X315165Y-3645D02*
X339580Y-20740D01*
G01X326713Y-13135D02*
X338754Y-21566D01*
G01X314339Y-4471D02*
X326713Y-13135D01*
G01X268078Y63604D02*
X315165Y-3645D01*
G01X332715Y-25622D02*
X309283Y-9214D01*
G01X331889Y-26448D02*
X308457Y-10040D01*
G01X337891Y-33013D02*
X332715Y-25622D01*
G01X336802Y-33463D02*
X331889Y-26448D01*
G01X338082Y-34103D02*
X337891Y-33013D01*
G01X336932Y-34204D02*
X336802Y-33464D01*
G01X338082Y-34668D02*
Y-34103D01*
G01X336932Y-34704D02*
Y-34204D01*
G01X339442Y-36479D02*
G02X338082Y-34668I607J1872D01*
G01X336932Y-34711D02*
G02Y-34704I3118J3D01*
G01X327852Y-33545D02*
X327882Y-34673D01*
G01X326732Y-34711D02*
X326710Y-33879D01*
G01X326192Y-30795D02*
X327852Y-33545D01*
G01X326710Y-33879D02*
X325275Y-31502D01*
G01X326100Y-30700D02*
X326192Y-30795D01*
G01X325275Y-31502D02*
X323845Y-30030D01*
G01X324595Y-29150D02*
X326100Y-30700D01*
G01X325275Y-31502D02*
X323845Y-30030D01*
G01X303244Y-14188D02*
X324595Y-29150D01*
G01X323845Y-30030D02*
X302584Y-15130D01*
G01X303121Y-14065D02*
G03X303244Y-14188I410J287D01*
G01X302584Y-15130D02*
G02X302179Y-14725I947J1352D01*
G01X335396Y-23960D02*
X311035Y-6903D01*
G01X336222Y-23134D02*
X311861Y-6077D01*
G01X341838Y-33157D02*
X335396Y-23960D01*
G01X342927Y-32706D02*
X336222Y-23134D01*
G01X341982Y-33976D02*
X341838Y-33157D01*
G01X343132Y-33876D02*
X342927Y-32706D01*
G01X341982Y-37770D02*
Y-33976D01*
G01X343132Y-37887D02*
Y-33876D01*
G01X341705Y-39112D02*
X341981Y-37770D01*
G01X342843Y-39293D02*
X343132Y-37887D01*
G01X341677Y-39369D02*
X341705Y-39112D01*
G01X342833Y-39380D02*
X342843Y-39293D01*
G01X341911Y-41972D02*
X341677Y-39369D01*
G01X343061Y-41920D02*
X342833Y-39380D01*
G01X341911Y-44688D02*
Y-41972D01*
G01X343061Y-44653D02*
Y-41920D01*
G01X331711Y-41972D02*
Y-44120D01*
G01X332861Y-41893D02*
Y-44046D01*
G01X331429Y-39924D02*
X331711Y-41972D01*
G01X332593Y-39940D02*
X332861Y-41893D01*
G01X331782Y-37788D02*
X331429Y-39924D01*
G01X332932Y-37883D02*
X332593Y-39940D01*
G01X331782Y-36316D02*
Y-37788D01*
G01X332932Y-36318D02*
Y-37883D01*
G01X331101Y-32464D02*
X331781Y-36315D01*
G01X332190Y-32013D02*
X332915Y-36118D01*
G01X328320Y-28493D02*
X331101Y-32464D01*
G01X329146Y-27667D02*
X332190Y-32013D01*
G01X305086Y-12224D02*
X328320Y-28493D01*
G01X305912Y-11398D02*
X329146Y-27667D01*
G01X336222Y-23134D02*
X311861Y-6077D01*
G01X335396Y-23960D02*
X311035Y-6903D01*
G01X342927Y-32706D02*
X336222Y-23134D01*
G01X341838Y-33157D02*
X335396Y-23960D01*
G01X343132Y-33876D02*
X342927Y-32706D01*
G01X341982Y-33976D02*
X341838Y-33157D01*
G01X343132Y-37887D02*
Y-33876D01*
G01X341982Y-37770D02*
Y-33976D01*
G01X342843Y-39293D02*
X343132Y-37887D01*
G01X341705Y-39112D02*
X341981Y-37770D01*
G01X342833Y-39380D02*
X342843Y-39293D01*
G01X341677Y-39369D02*
X341705Y-39112D01*
G01X343061Y-41920D02*
X342833Y-39380D01*
G01X341911Y-41972D02*
X341677Y-39369D01*
G01X343061Y-44653D02*
Y-41920D01*
G01X341911Y-44688D02*
Y-41972D01*
G01X332861Y-41893D02*
Y-44046D01*
G01X331711Y-41972D02*
Y-44120D01*
G01X332593Y-39940D02*
X332861Y-41893D01*
G01X331429Y-39924D02*
X331711Y-41972D01*
G01X332932Y-37883D02*
X332593Y-39940D01*
G01X331782Y-37788D02*
X331429Y-39924D01*
G01X332932Y-36318D02*
Y-37883D01*
G01X331782Y-36316D02*
Y-37788D01*
G01X332190Y-32013D02*
X332915Y-36118D01*
G01X331101Y-32464D02*
X331781Y-36315D01*
G01X329146Y-27667D02*
X332190Y-32013D01*
G01X328320Y-28493D02*
X331101Y-32464D01*
G01X305912Y-11398D02*
X329146Y-27667D01*
G01X305086Y-12224D02*
X328320Y-28493D01*
G01X299587Y-18492D02*
G02X299182Y-18087I947J1352D01*
G01X300124Y-17427D02*
G03X300247Y-17550I410J287D01*
G01X316702Y-30475D02*
X299587Y-18492D01*
G01X300247Y-17550D02*
X317362Y-29533D01*
G01X316823Y-30598D02*
G03X316702Y-30475I-411J-284D01*
G01X317362Y-29533D02*
G02X317767Y-29939I-948J-1351D01*
G01X318575Y-33099D02*
X316824Y-30598D01*
G01X317767Y-29939D02*
X319517Y-32439D01*
G01X318627Y-33195D02*
G03X318575Y-33099I-462J-188D01*
G01X319517Y-32439D02*
G02X319690Y-32754I-1351J-947D01*
G01X320851Y-38564D02*
X318627Y-33195D01*
G01X319690Y-32754D02*
X321914Y-38124D01*
G01X321511Y-41764D02*
X321029Y-39032D01*
G01X322118Y-38581D02*
X322661Y-41663D01*
G01X321511Y-44688D02*
Y-41764D01*
G01X322661Y-41663D02*
Y-44653D01*
G01Y-41663D02*
Y-44653D01*
G01X321511Y-44688D02*
Y-41764D01*
G01X322118Y-38581D02*
X322661Y-41663D01*
G01X321511Y-41764D02*
X321029Y-39032D01*
G01X319690Y-32754D02*
X321914Y-38124D01*
G01X320851Y-38564D02*
X318627Y-33195D01*
G01X319517Y-32439D02*
G02X319690Y-32754I-1351J-947D01*
G01X318627Y-33195D02*
G03X318575Y-33099I-462J-188D01*
G01X317767Y-29939D02*
X319517Y-32439D01*
G01X318575Y-33099D02*
X316824Y-30598D01*
G01X317362Y-29533D02*
G02X317767Y-29939I-948J-1351D01*
G01X316823Y-30598D02*
G03X316702Y-30475I-411J-284D01*
G01X300247Y-17550D02*
X317362Y-29533D01*
G01X316702Y-30475D02*
X299587Y-18492D01*
G01X300124Y-17427D02*
G03X300247Y-17550I410J287D01*
G01X299587Y-18492D02*
G02X299182Y-18087I947J1352D01*
G01X328462Y94860D02*
X334467Y128913D01*
G01X335619Y128823D02*
X329454Y93857D01*
G01X326836Y85632D02*
X328462Y94858D01*
G01X329454Y93857D02*
X328004Y85632D01*
G01X334558Y41840D02*
X326836Y85632D01*
G01X328004D02*
X335647Y42291D01*
G01X337062Y38266D02*
X334558Y41840D01*
G01X335647Y42291D02*
X346358Y27003D01*
G01X340060Y33987D02*
X337062Y38266D01*
G01X335647Y42291D02*
X346358Y27003D01*
G01X345532Y26177D02*
X340060Y33987D01*
G01X335647Y42291D02*
X346358Y27003D01*
G01X367646Y10694D02*
X345532Y26177D01*
G01X346358Y27003D02*
X368399Y11572D01*
G01X346358Y27003D02*
X368399Y11572D01*
G01X367646Y10694D02*
X345532Y26177D01*
G01X335647Y42291D02*
X346358Y27003D01*
G01X337062Y38266D02*
X334558Y41840D01*
G01X340060Y33987D02*
X337062Y38266D01*
G01X345532Y26177D02*
X340060Y33987D01*
G01X328004Y85632D02*
X335647Y42291D01*
G01X334558Y41840D02*
X326836Y85632D01*
G01X329454Y93857D02*
X328004Y85632D01*
G01X326836D02*
X328462Y94858D01*
G01X335619Y128823D02*
X329454Y93857D01*
G01X328462Y94860D02*
X334467Y128913D01*
G01X319222Y86610D02*
X326575Y128314D01*
G01X320390Y86610D02*
X327725Y128213D01*
G01X320476Y79498D02*
X319222Y86610D01*
G01X321644Y79498D02*
X320390Y86610D01*
G01X323440Y62687D02*
X320476Y79498D01*
G01X327503Y46274D02*
X321644Y79498D01*
G01X326414Y45823D02*
X323440Y62687D01*
G01X327503Y46274D02*
X321644Y79498D01*
G01X341555Y24200D02*
X326414Y45823D01*
G01X342383Y25023D02*
X327503Y46274D01*
G01X364105Y8189D02*
X341555Y24200D01*
G01X364842Y9077D02*
X342383Y25023D01*
G01X320390Y86610D02*
X327725Y128213D01*
G01X319222Y86610D02*
X326575Y128314D01*
G01X321644Y79498D02*
X320390Y86610D01*
G01X320476Y79498D02*
X319222Y86610D01*
G01X327503Y46274D02*
X321644Y79498D01*
G01X323440Y62687D02*
X320476Y79498D01*
G01X326414Y45823D02*
X323440Y62687D01*
G01X342383Y25023D02*
X327503Y46274D01*
G01X341555Y24200D02*
X326414Y45823D01*
G01X364842Y9077D02*
X342383Y25023D01*
G01X364105Y8189D02*
X341555Y24200D01*
G01X313319Y97801D02*
X318700Y128314D01*
G01X314487Y97801D02*
X319850Y128213D01*
G01X313673Y95790D02*
X313319Y97801D01*
G01X323757Y45228D02*
X314487Y97801D01*
G01X322668Y44777D02*
X313673Y95790D01*
G01X323757Y45228D02*
X314487Y97801D01*
G01X330956Y32941D02*
X322668Y44777D01*
G01X340039Y21974D02*
X323757Y45228D01*
G01X339213Y21148D02*
X330956Y32941D01*
G01X340039Y21974D02*
X323757Y45228D01*
G01X314806Y35881D02*
X315046Y35303D01*
G01X316109Y35743D02*
X315917Y36206D01*
G01X302661Y104175D02*
X314806Y35881D01*
G01X315917Y36206D02*
X303794Y104376D01*
G01X314487Y97801D02*
X319850Y128213D01*
G01X313319Y97801D02*
X318700Y128314D01*
G01X323757Y45228D02*
X314487Y97801D01*
G01X313673Y95790D02*
X313319Y97801D01*
G01X322668Y44777D02*
X313673Y95790D01*
G01X340039Y21974D02*
X323757Y45228D01*
G01X330956Y32941D02*
X322668Y44777D01*
G01X339213Y21148D02*
X330956Y32941D01*
G01X315917Y36206D02*
X303794Y104376D01*
G01X302661Y104175D02*
X314806Y35881D01*
G01X316109Y35743D02*
X315917Y36206D01*
G01X314806Y35881D02*
X315046Y35303D01*
G01X309512Y90016D02*
X306773Y105552D01*
G01X307941D02*
X310587Y90544D01*
G01X318839Y37118D02*
X309512Y90015D01*
G01X315287Y63891D02*
X319928Y37569D01*
G01X310587Y90544D02*
X315287Y63891D01*
G01X295183Y103496D02*
X306164Y41219D01*
G01X307253Y41670D02*
X296333Y103599D01*
G01X315287Y63891D02*
X319928Y37569D01*
G01X318839Y37118D02*
X309512Y90015D01*
G01X310587Y90544D02*
X315287Y63891D01*
G01X318839Y37118D02*
X309512Y90015D01*
G01X307941Y105552D02*
X310587Y90544D01*
G01X309512Y90016D02*
X306773Y105552D01*
G01X307253Y41670D02*
X296333Y103599D01*
G01X295183Y103496D02*
X306164Y41219D01*
G01X299518Y44142D02*
X287181Y128456D01*
G01X300656Y44308D02*
X288331Y128540D01*
G01X300656Y44308D02*
X288331Y128540D01*
G01X299518Y44142D02*
X287181Y128456D01*
G01X295010Y45999D02*
X280559Y127952D01*
G01X293921Y45548D02*
X279487Y127405D01*
G01X295010Y45999D02*
X280559Y127952D01*
G01X295010Y45999D02*
X280559Y127952D01*
G01X293921Y45548D02*
X279487Y127405D01*
G01X271737Y126728D02*
X284980Y51626D01*
G01X272826Y127178D02*
X286069Y52077D01*
G01X272826Y127178D02*
X286069Y52077D01*
G01X271737Y126728D02*
X284980Y51626D01*
G01X318861Y179798D02*
X317566Y183143D01*
G01X326032Y167568D02*
X318861Y179798D01*
G01X319900Y180300D02*
X327025Y168150D01*
G01X331820Y160659D02*
X326145Y167409D01*
G01X332700Y161400D02*
X332712Y161386D01*
G01X327025Y168150D02*
X332700Y161400D01*
G01X334326Y157487D02*
X331820Y160659D01*
G01X332712Y161386D02*
X335449Y157922D01*
G01X334417Y156194D02*
X334326Y157487D01*
G01X335449Y157922D02*
X335565Y156275D01*
G01X336506Y151616D02*
G02X334417Y156194I5087J5087D01*
G01X335565Y156275D02*
G03X337320Y152430I6028J428D01*
G01X337380Y150742D02*
X336506Y151616D01*
G01X337320Y152430D02*
X338194Y151556D01*
G01X338260Y148620D02*
G03X337380Y150742I-3002J-1D01*
G01X338194Y151556D02*
G02X339410Y148620I-2936J-2936D01*
G01X338260Y138459D02*
Y148620D01*
G01X339410D02*
Y138460D01*
G01X336602Y134460D02*
G03X338260Y138459I-3999J4001D01*
G01X339410Y138460D02*
G02X337416Y133646I-6808J0D01*
G01X336176Y134034D02*
X336602Y134460D01*
G01X337416Y133646D02*
X336990Y133220D01*
G01X334450Y129863D02*
G02X336176Y134034I5897J3D01*
G01X336990Y133220D02*
G03X335601Y129873I3357J-3355D01*
G01X336990Y133220D02*
G03X335601Y129873I3357J-3355D01*
G01X334450Y129863D02*
G02X336176Y134034I5897J3D01*
G01X337416Y133646D02*
X336990Y133220D01*
G01X336176Y134034D02*
X336602Y134460D01*
G01X339410Y138460D02*
G02X337416Y133646I-6808J0D01*
G01X336602Y134460D02*
G03X338260Y138459I-3999J4001D01*
G01X339410Y148620D02*
Y138460D01*
G01X338260Y138459D02*
Y148620D01*
G01X338194Y151556D02*
G02X339410Y148620I-2936J-2936D01*
G01X338260D02*
G03X337380Y150742I-3002J-1D01*
G01X337320Y152430D02*
X338194Y151556D01*
G01X337380Y150742D02*
X336506Y151616D01*
G01X335565Y156275D02*
G03X337320Y152430I6028J428D01*
G01X336506Y151616D02*
G02X334417Y156194I5087J5087D01*
G01X335449Y157922D02*
X335565Y156275D01*
G01X334417Y156194D02*
X334326Y157487D01*
G01X332712Y161386D02*
X335449Y157922D01*
G01X334326Y157487D02*
X331820Y160659D01*
G01X332700Y161400D02*
X332712Y161386D01*
G01X331820Y160659D02*
X326145Y167409D01*
G01X327025Y168150D02*
X332700Y161400D01*
G01X331820Y160659D02*
X326145Y167409D01*
G01X319900Y180300D02*
X327025Y168150D01*
G01X326032Y167568D02*
X318861Y179798D01*
G01D02*
X317566Y183143D01*
G01X326100Y158900D02*
X309238Y188208D01*
G01X327193Y159307D02*
X310297Y188674D01*
G01X326525Y156702D02*
X326100Y158900D01*
G01X327676Y156812D02*
X327193Y159307D01*
G01X328631Y151616D02*
G02X326525Y156702I5088J5086D01*
G01X329445Y152430D02*
G02X327676Y156702I4274J4272D01*
G01X329505Y150742D02*
X328631Y151616D01*
G01X330319Y151556D02*
X329445Y152430D01*
G01X330385Y148620D02*
G03X329505Y150742I-3002J-1D01*
G01X331535Y148620D02*
G03X330319Y151556I-4152J0D01*
G01X330385Y138459D02*
Y148620D01*
G01X331535Y138460D02*
Y148620D01*
G01X328727Y134460D02*
G03X330385Y138459I-3999J4001D01*
G01X329541Y133646D02*
G03X331535Y138460I-4814J4814D01*
G01X328301Y134034D02*
X328727Y134460D01*
G01X329115Y133220D02*
X329541Y133646D01*
G01X326575Y129863D02*
G02X328301Y134034I5897J3D01*
G01X327725Y129864D02*
G02X329115Y133220I4746J0D01*
G01X326575Y128314D02*
Y129863D01*
G01X327725Y128213D02*
Y129864D01*
G01X327193Y159307D02*
X310297Y188674D01*
G01X326100Y158900D02*
X309238Y188208D01*
G01X327676Y156812D02*
X327193Y159307D01*
G01X326525Y156702D02*
X326100Y158900D01*
G01X329445Y152430D02*
G02X327676Y156702I4274J4272D01*
G01X328631Y151616D02*
G02X326525Y156702I5088J5086D01*
G01X330319Y151556D02*
X329445Y152430D01*
G01X329505Y150742D02*
X328631Y151616D01*
G01X331535Y148620D02*
G03X330319Y151556I-4152J0D01*
G01X330385Y148620D02*
G03X329505Y150742I-3002J-1D01*
G01X331535Y138460D02*
Y148620D01*
G01X330385Y138459D02*
Y148620D01*
G01X329541Y133646D02*
G03X331535Y138460I-4814J4814D01*
G01X328727Y134460D02*
G03X330385Y138459I-3999J4001D01*
G01X329115Y133220D02*
X329541Y133646D01*
G01X328301Y134034D02*
X328727Y134460D01*
G01X327725Y129864D02*
G02X329115Y133220I4746J0D01*
G01X326575Y129863D02*
G02X328301Y134034I5897J3D01*
G01X327725Y128213D02*
Y129864D01*
G01X326575Y128314D02*
Y129863D01*
G01X317700Y160800D02*
X307234Y184028D01*
G01X318795Y161170D02*
X308244Y184588D01*
G01X318650Y156702D02*
X317700Y160800D01*
G01X319801Y156834D02*
X318795Y161170D01*
G01X320756Y151616D02*
G02X318650Y156702I5088J5086D01*
G01X321570Y152430D02*
G02X319801Y156702I4274J4272D01*
G01X321630Y150742D02*
X320756Y151616D01*
G01X322444Y151556D02*
X321570Y152430D01*
G01X322510Y148620D02*
G03X321630Y150742I-3002J-1D01*
G01X323660Y148620D02*
G03X322444Y151556I-4152J0D01*
G01X322510Y138459D02*
Y148620D01*
G01X323660Y138460D02*
Y148620D01*
G01X320852Y134460D02*
G03X322510Y138459I-3999J4001D01*
G01X321666Y133646D02*
G03X323660Y138460I-4814J4814D01*
G01X320426Y134034D02*
X320852Y134460D01*
G01X321240Y133220D02*
X321666Y133646D01*
G01X318700Y129863D02*
G02X320426Y134034I5897J3D01*
G01X319850Y129864D02*
G02X321240Y133220I4746J0D01*
G01X318700Y128314D02*
Y129863D01*
G01X319850Y128213D02*
Y129864D01*
G01X301788Y109132D02*
X302661Y104177D01*
G01X303794Y104376D02*
X302944Y109200D01*
G01X302931Y129413D02*
X301788Y109132D01*
G01X302944Y109200D02*
X304081Y129349D01*
G01X302018Y132702D02*
G02X302930Y130500I-2202J-2202D01*
G01X304081D02*
G03X302832Y133516I-4266J0D01*
G01X301490Y133230D02*
X302018Y132702D01*
G01X302832Y133516D02*
X302304Y134044D01*
G01X299041Y139144D02*
G03X301490Y133230I8365J0D01*
G01X302304Y134044D02*
G02X300191Y139145I5101J5101D01*
G01X299041Y147640D02*
Y139144D01*
G01X300191Y139145D02*
Y147640D01*
G01X300994Y152357D02*
G03X299041Y147640I4716J-4716D01*
G01X300191D02*
G02X301807Y151543I5519J1D01*
G01X301322Y152684D02*
X300994Y152357D01*
G01X301807Y151543D02*
X302135Y151870D01*
G01X302924Y156448D02*
G02X301322Y152684I-5473J106D01*
G01X302135Y151870D02*
G03X304074Y156437I-4684J4684D01*
G01X302924Y157700D02*
Y156448D01*
G01X304074Y156437D02*
Y157834D01*
G01X284034Y194956D02*
X302657Y158851D01*
G01X303755Y159232D02*
X285100Y195400D01*
G01X318795Y161170D02*
X308244Y184588D01*
G01X317700Y160800D02*
X307234Y184028D01*
G01X319801Y156834D02*
X318795Y161170D01*
G01X318650Y156702D02*
X317700Y160800D01*
G01X321570Y152430D02*
G02X319801Y156702I4274J4272D01*
G01X320756Y151616D02*
G02X318650Y156702I5088J5086D01*
G01X322444Y151556D02*
X321570Y152430D01*
G01X321630Y150742D02*
X320756Y151616D01*
G01X323660Y148620D02*
G03X322444Y151556I-4152J0D01*
G01X322510Y148620D02*
G03X321630Y150742I-3002J-1D01*
G01X323660Y138460D02*
Y148620D01*
G01X322510Y138459D02*
Y148620D01*
G01X321666Y133646D02*
G03X323660Y138460I-4814J4814D01*
G01X320852Y134460D02*
G03X322510Y138459I-3999J4001D01*
G01X321240Y133220D02*
X321666Y133646D01*
G01X320426Y134034D02*
X320852Y134460D01*
G01X319850Y129864D02*
G02X321240Y133220I4746J0D01*
G01X318700Y129863D02*
G02X320426Y134034I5897J3D01*
G01X319850Y128213D02*
Y129864D01*
G01X318700Y128314D02*
Y129863D01*
G01X303755Y159232D02*
X285100Y195400D01*
G01X284034Y194956D02*
X302657Y158851D01*
G01X304074Y156437D02*
Y157834D01*
G01X302924Y157700D02*
Y156448D01*
G01X302135Y151870D02*
G03X304074Y156437I-4684J4684D01*
G01X302924Y156448D02*
G02X301322Y152684I-5473J106D01*
G01X301807Y151543D02*
X302135Y151870D01*
G01X301322Y152684D02*
X300994Y152357D01*
G01X300191Y147640D02*
G02X301807Y151543I5519J1D01*
G01X300994Y152357D02*
G03X299041Y147640I4716J-4716D01*
G01X300191Y139145D02*
Y147640D01*
G01X299041D02*
Y139144D01*
G01X302304Y134044D02*
G02X300191Y139145I5101J5101D01*
G01X299041Y139144D02*
G03X301490Y133230I8365J0D01*
G01X302832Y133516D02*
X302304Y134044D01*
G01X301490Y133230D02*
X302018Y132702D01*
G01X304081Y130500D02*
G03X302832Y133516I-4266J0D01*
G01X302018Y132702D02*
G02X302930Y130500I-2202J-2202D01*
G01X302944Y109200D02*
X304081Y129349D01*
G01X302931Y129413D02*
X301788Y109132D01*
G01X303794Y104376D02*
X302944Y109200D01*
G01X301788Y109132D02*
X302661Y104177D01*
G01X293123Y189675D02*
X311756Y158701D01*
G01X310634Y158335D02*
X292367Y188700D01*
G01X293123Y189675D02*
X311756Y158701D01*
G01X310756Y156955D02*
X310634Y158335D01*
G01X311902Y157059D02*
X311948Y156560D01*
G01X311756Y158701D02*
X311902Y157059D01*
G01X310802Y156457D02*
X310756Y156956D01*
G01X311902Y157059D02*
X311948Y156560D01*
G01X311756Y158701D02*
X311902Y157059D01*
G01X309197Y152684D02*
G03X310799Y156451I-3871J3870D01*
G01X311949Y156429D02*
G02X310010Y151870I-6623J125D01*
G01X311950Y156554D02*
G02X311949Y156429I-6624J-10D01*
G01X308869Y152357D02*
X309197Y152684D01*
G01X310010Y151870D02*
X309682Y151543D01*
G01X306916Y147640D02*
G02X308869Y152357I6669J1D01*
G01X309682Y151543D02*
G03X308066Y147640I3903J-3902D01*
G01X306916Y139144D02*
Y147640D01*
G01X308066D02*
Y139145D01*
G01X309365Y133230D02*
G02X306916Y139144I5916J5914D01*
G01X308066Y139145D02*
G03X310179Y134044I7214J0D01*
G01X309893Y132702D02*
X309365Y133230D01*
G01X310179Y134044D02*
X310707Y133516D01*
G01X310805Y130500D02*
G03X309893Y132702I-3114J0D01*
G01X310707Y133516D02*
G02X311956Y130500I-3017J-3016D01*
G01X310809Y128450D02*
Y128849D01*
G01X311959D02*
Y128349D01*
G01X306773Y105552D02*
X310809Y128450D01*
G01X311959Y128349D02*
X307941Y105552D01*
G01X295119Y117045D02*
X295183Y103496D01*
G01X296333Y103599D02*
X296206Y130500D01*
G01X294143Y132702D02*
G02X295055Y130500I-2202J-2202D01*
G01X296206D02*
G03X294957Y133516I-4266J0D01*
G01X293615Y133230D02*
X294143Y132702D01*
G01X294957Y133516D02*
X294429Y134044D01*
G01X291166Y139144D02*
G03X293615Y133230I8365J0D01*
G01X294429Y134044D02*
G02X292316Y139145I5101J5101D01*
G01X291166Y147640D02*
Y139144D01*
G01X292316Y139145D02*
Y147640D01*
G01X293119Y152357D02*
G03X291166Y147640I4716J-4716D01*
G01X292316D02*
G02X293932Y151543I5519J1D01*
G01X293447Y152684D02*
X293119Y152357D01*
G01X293932Y151543D02*
X294260Y151870D01*
G01X295049Y156554D02*
G02X293447Y152684I-5473J-1D01*
G01X294260Y151870D02*
G03X296200Y156554I-4684J4684D01*
G01X295049Y157522D02*
Y156554D01*
G01X296200D02*
Y157704D01*
G01X292534Y165159D02*
X295049Y157522D01*
G01X296200Y157704D02*
X293600Y165600D01*
G01X272492Y204653D02*
X292534Y165159D01*
G01X293600Y165600D02*
X279299Y193781D01*
G01X311959Y128349D02*
X307941Y105552D01*
G01X306773D02*
X310809Y128450D01*
G01X311959Y128849D02*
Y128349D01*
G01X310809Y128450D02*
Y128849D01*
G01X310707Y133516D02*
G02X311956Y130500I-3017J-3016D01*
G01X310805D02*
G03X309893Y132702I-3114J0D01*
G01X310179Y134044D02*
X310707Y133516D01*
G01X309893Y132702D02*
X309365Y133230D01*
G01X308066Y139145D02*
G03X310179Y134044I7214J0D01*
G01X309365Y133230D02*
G02X306916Y139144I5916J5914D01*
G01X308066Y147640D02*
Y139145D01*
G01X306916Y139144D02*
Y147640D01*
G01X309682Y151543D02*
G03X308066Y147640I3903J-3902D01*
G01X306916D02*
G02X308869Y152357I6669J1D01*
G01X310010Y151870D02*
X309682Y151543D01*
G01X308869Y152357D02*
X309197Y152684D01*
G01X311949Y156429D02*
G02X310010Y151870I-6623J125D01*
G01X309197Y152684D02*
G03X310799Y156451I-3871J3870D01*
G01X311950Y156554D02*
G02X311949Y156429I-6624J-10D01*
G01X309197Y152684D02*
G03X310799Y156451I-3871J3870D01*
G01X311902Y157059D02*
X311948Y156560D01*
G01X310756Y156955D02*
X310634Y158335D01*
G01X310802Y156457D02*
X310756Y156956D01*
G01X311756Y158701D02*
X311902Y157059D01*
G01X310756Y156955D02*
X310634Y158335D01*
G01X310802Y156457D02*
X310756Y156956D01*
G01X293123Y189675D02*
X311756Y158701D01*
G01X310634Y158335D02*
X292367Y188700D01*
G01X272492Y204653D02*
X292534Y165159D01*
G01X272492Y204653D02*
X292534Y165159D01*
G01X272492Y204653D02*
X292534Y165159D01*
G01X293600Y165600D02*
X279299Y193781D01*
G01X272492Y204653D02*
X292534Y165159D01*
G01X296200Y157704D02*
X293600Y165600D01*
G01X292534Y165159D02*
X295049Y157522D01*
G01X296200Y156554D02*
Y157704D01*
G01X295049Y157522D02*
Y156554D01*
G01X294260Y151870D02*
G03X296200Y156554I-4684J4684D01*
G01X295049D02*
G02X293447Y152684I-5473J-1D01*
G01X293932Y151543D02*
X294260Y151870D01*
G01X293447Y152684D02*
X293119Y152357D01*
G01X292316Y147640D02*
G02X293932Y151543I5519J1D01*
G01X293119Y152357D02*
G03X291166Y147640I4716J-4716D01*
G01X292316Y139145D02*
Y147640D01*
G01X291166D02*
Y139144D01*
G01X294429Y134044D02*
G02X292316Y139145I5101J5101D01*
G01X291166Y139144D02*
G03X293615Y133230I8365J0D01*
G01X294957Y133516D02*
X294429Y134044D01*
G01X293615Y133230D02*
X294143Y132702D01*
G01X296206Y130500D02*
G03X294957Y133516I-4266J0D01*
G01X294143Y132702D02*
G02X295055Y130500I-2202J-2202D01*
G01X296333Y103599D02*
X296206Y130500D01*
G01X295119Y117045D02*
X295183Y103496D01*
G01X285846Y160836D02*
X267496Y200174D01*
G01X287173Y157487D02*
X285846Y160836D01*
G01X288325Y157704D02*
X286900Y161300D01*
G01X287174Y156554D02*
Y157487D01*
G01X288325Y156554D02*
Y157704D01*
G01X285572Y152684D02*
G03X287174Y156554I-3871J3869D01*
G01X286385Y151870D02*
G03X288325Y156554I-4684J4684D01*
G01X285244Y152357D02*
X285572Y152684D01*
G01X286057Y151543D02*
X286385Y151870D01*
G01X283291Y147640D02*
G02X285244Y152357I6669J1D01*
G01X284441Y147640D02*
G02X286057Y151543I5519J1D01*
G01X283291Y139144D02*
Y147640D01*
G01X284441Y139145D02*
Y147640D01*
G01X285740Y133230D02*
G02X283291Y139144I5916J5914D01*
G01X286554Y134044D02*
G02X284441Y139145I5101J5101D01*
G01X286268Y132702D02*
X285740Y133230D01*
G01X287082Y133516D02*
X286554Y134044D01*
G01X287180Y130500D02*
G03X286268Y132702I-3114J0D01*
G01X288331Y130500D02*
G03X287082Y133516I-4266J0D01*
G01X287180Y129270D02*
Y130500D01*
G01X288331Y128540D02*
Y130500D01*
G01X287181Y128456D02*
Y128965D01*
G01X288331Y128540D02*
Y130500D01*
G01X285846Y160836D02*
X267496Y200174D01*
G01X288325Y157704D02*
X286900Y161300D01*
G01X287173Y157487D02*
X285846Y160836D01*
G01X288325Y156554D02*
Y157704D01*
G01X287174Y156554D02*
Y157487D01*
G01X286385Y151870D02*
G03X288325Y156554I-4684J4684D01*
G01X285572Y152684D02*
G03X287174Y156554I-3871J3869D01*
G01X286057Y151543D02*
X286385Y151870D01*
G01X285244Y152357D02*
X285572Y152684D01*
G01X284441Y147640D02*
G02X286057Y151543I5519J1D01*
G01X283291Y147640D02*
G02X285244Y152357I6669J1D01*
G01X284441Y139145D02*
Y147640D01*
G01X283291Y139144D02*
Y147640D01*
G01X286554Y134044D02*
G02X284441Y139145I5101J5101D01*
G01X285740Y133230D02*
G02X283291Y139144I5916J5914D01*
G01X287082Y133516D02*
X286554Y134044D01*
G01X286268Y132702D02*
X285740Y133230D01*
G01X288331Y130500D02*
G03X287082Y133516I-4266J0D01*
G01X287180Y130500D02*
G03X286268Y132702I-3114J0D01*
G01X288331Y128540D02*
Y130500D01*
G01X287180Y129270D02*
Y130500D01*
G01X287181Y128456D02*
Y128965D01*
G01X279143Y158790D02*
X271713Y180610D01*
G01X280268Y159055D02*
X272805Y180991D01*
G01X279310Y157551D02*
X279143Y158790D01*
G01X280461Y157622D02*
X280268Y159055D01*
G01X279299Y156554D02*
X279310Y157551D01*
G01X280450Y156554D02*
Y156637D01*
G01X277697Y152684D02*
G03X279299Y156554I-3871J3869D01*
G01X278510Y151870D02*
G03X280450Y156554I-4684J4684D01*
G01X277369Y152357D02*
X277697Y152684D01*
G01X278182Y151543D02*
X278510Y151870D01*
G01X275416Y147640D02*
G02X277369Y152357I6669J1D01*
G01X276566Y147640D02*
G02X278182Y151543I5519J1D01*
G01X275416Y139144D02*
Y147640D01*
G01X276566Y139145D02*
Y147640D01*
G01X277865Y133230D02*
G02X275416Y139144I5916J5914D01*
G01X278679Y134044D02*
G02X276566Y139145I5101J5101D01*
G01X278393Y132702D02*
X277865Y133230D01*
G01X279207Y133516D02*
X278679Y134044D01*
G01X279305Y130500D02*
G03X278393Y132702I-3114J0D01*
G01X280456Y130500D02*
G03X279207Y133516I-4266J0D01*
G01X279305Y129270D02*
Y130500D01*
G01X280456Y128540D02*
Y130500D01*
G01X279306Y128439D02*
Y128965D01*
G01X280456Y128540D02*
Y130500D01*
G01X279487Y127405D02*
X279306Y128439D01*
G01X280559Y127952D02*
X280456Y128540D01*
G01X280268Y159055D02*
X272805Y180991D01*
G01X279143Y158790D02*
X271713Y180610D01*
G01X280461Y157622D02*
X280268Y159055D01*
G01X279310Y157551D02*
X279143Y158790D01*
G01X280450Y156554D02*
Y156637D01*
G01X279299Y156554D02*
X279310Y157551D01*
G01X278510Y151870D02*
G03X280450Y156554I-4684J4684D01*
G01X277697Y152684D02*
G03X279299Y156554I-3871J3869D01*
G01X278182Y151543D02*
X278510Y151870D01*
G01X277369Y152357D02*
X277697Y152684D01*
G01X276566Y147640D02*
G02X278182Y151543I5519J1D01*
G01X275416Y147640D02*
G02X277369Y152357I6669J1D01*
G01X276566Y139145D02*
Y147640D01*
G01X275416Y139144D02*
Y147640D01*
G01X278679Y134044D02*
G02X276566Y139145I5101J5101D01*
G01X277865Y133230D02*
G02X275416Y139144I5916J5914D01*
G01X279207Y133516D02*
X278679Y134044D01*
G01X278393Y132702D02*
X277865Y133230D01*
G01X280456Y130500D02*
G03X279207Y133516I-4266J0D01*
G01X279305Y130500D02*
G03X278393Y132702I-3114J0D01*
G01X280456Y128540D02*
Y130500D01*
G01X279305Y129270D02*
Y130500D01*
G01X279306Y128439D02*
Y128965D01*
G01X280559Y127952D02*
X280456Y128540D01*
G01X279487Y127405D02*
X279306Y128439D01*
G01X279487Y127405D02*
X279306Y128439D01*
G01X271436D02*
X271737Y126728D01*
G01X272586Y128540D02*
X272826Y127179D01*
G01X271436Y128965D02*
Y128439D01*
G01X272586Y130500D02*
Y128540D01*
G01X271435Y130500D02*
Y129270D01*
G01X272586Y130500D02*
Y128540D01*
G01X270523Y132702D02*
G02X271435Y130500I-2202J-2202D01*
G01X271337Y133516D02*
G02X272586Y130500I-3017J-3016D01*
G01X269995Y133230D02*
X270523Y132702D01*
G01X270809Y134044D02*
X271337Y133516D01*
G01X267546Y139144D02*
G03X269995Y133230I8365J0D01*
G01X268696Y139145D02*
G03X270809Y134044I7214J0D01*
G01X267546Y147640D02*
Y139144D01*
G01X268696Y147640D02*
Y139145D01*
G01X269499Y152357D02*
G03X267546Y147640I4716J-4716D01*
G01X270312Y151543D02*
G03X268696Y147640I3903J-3902D01*
G01X269827Y152684D02*
X269499Y152357D01*
G01X270640Y151870D02*
X270312Y151543D01*
G01X271429Y156554D02*
G02X269827Y152684I-5473J-1D01*
G01X272580Y156554D02*
G02X270640Y151870I-6624J0D01*
G01X271430Y158102D02*
Y156553D01*
G01X272580Y158266D02*
Y156554D01*
G01X268300Y168900D02*
X271430Y158102D01*
G01X269376Y169321D02*
X272580Y158266D01*
G01X272586Y128540D02*
X272826Y127179D01*
G01X271436Y128439D02*
X271737Y126728D01*
G01X272586Y130500D02*
Y128540D01*
G01X271436Y128965D02*
Y128439D01*
G01X271435Y130500D02*
Y129270D01*
G01X271337Y133516D02*
G02X272586Y130500I-3017J-3016D01*
G01X270523Y132702D02*
G02X271435Y130500I-2202J-2202D01*
G01X270809Y134044D02*
X271337Y133516D01*
G01X269995Y133230D02*
X270523Y132702D01*
G01X268696Y139145D02*
G03X270809Y134044I7214J0D01*
G01X267546Y139144D02*
G03X269995Y133230I8365J0D01*
G01X268696Y147640D02*
Y139145D01*
G01X267546Y147640D02*
Y139144D01*
G01X270312Y151543D02*
G03X268696Y147640I3903J-3902D01*
G01X269499Y152357D02*
G03X267546Y147640I4716J-4716D01*
G01X270640Y151870D02*
X270312Y151543D01*
G01X269827Y152684D02*
X269499Y152357D01*
G01X272580Y156554D02*
G02X270640Y151870I-6624J0D01*
G01X271429Y156554D02*
G02X269827Y152684I-5473J-1D01*
G01X272580Y158266D02*
Y156554D01*
G01X271430Y158102D02*
Y156553D01*
G01X269376Y169321D02*
X272580Y158266D01*
G01X268300Y168900D02*
X271430Y158102D01*
G01X313535Y231308D02*
X313534D01*
G01X314051Y232336D02*
X314497Y232114D01*
G01X313806Y231172D02*
X313535Y231308D01*
G01X314051Y232336D02*
X314497Y232114D01*
G01X314050Y232336D02*
X314051D01*
G01X314994Y228137D02*
G03X313806Y231172I-4472J-1D01*
G01X314497Y232114D02*
G02X316144Y228138I-3976J-3976D01*
G01X314994Y217769D02*
Y228137D01*
G01X316144Y228138D02*
Y217770D01*
G01X316733Y214139D02*
G02X314994Y217769I2919J3630D01*
G01X316144Y217770D02*
G03X317500Y215000I3507J0D01*
G01X317018Y213854D02*
X316733Y214139D01*
G01X317500Y215000D02*
X317832Y214668D01*
G01X318450Y210399D02*
G03X317018Y213854I-4885J-1D01*
G01X317832Y214668D02*
G02X319600Y210400I-4268J-4268D01*
G01X318450Y208134D02*
Y210399D01*
G01X319600Y210400D02*
Y208100D01*
G01X318364Y206636D02*
X318450Y208134D01*
G01X319600Y208100D02*
X318400Y187300D01*
G01X318117Y202364D02*
X318203Y203861D01*
G01X319600Y208100D02*
X318400Y187300D01*
G01X317247Y187289D02*
X317957Y199588D01*
G01X319600Y208100D02*
X318400Y187300D01*
G01X317566Y183143D02*
X317247Y187289D01*
G01X318400Y187300D02*
X318700Y183400D01*
G01D02*
X319900Y180300D01*
G01X318700Y183400D02*
X319900Y180300D01*
G01X318400Y187300D02*
X318700Y183400D01*
G01X317566Y183143D02*
X317247Y187289D01*
G01X319600Y208100D02*
X318400Y187300D01*
G01X318364Y206636D02*
X318450Y208134D01*
G01X318117Y202364D02*
X318203Y203861D01*
G01X317247Y187289D02*
X317957Y199588D01*
G01X319600Y210400D02*
Y208100D01*
G01X318450Y208134D02*
Y210399D01*
G01X317832Y214668D02*
G02X319600Y210400I-4268J-4268D01*
G01X318450Y210399D02*
G03X317018Y213854I-4885J-1D01*
G01X317500Y215000D02*
X317832Y214668D01*
G01X317018Y213854D02*
X316733Y214139D01*
G01X316144Y217770D02*
G03X317500Y215000I3507J0D01*
G01X316733Y214139D02*
G02X314994Y217769I2919J3630D01*
G01X316144Y228138D02*
Y217770D01*
G01X314994Y217769D02*
Y228137D01*
G01X314497Y232114D02*
G02X316144Y228138I-3976J-3976D01*
G01X314994Y228137D02*
G03X313806Y231172I-4472J-1D01*
G01X314051Y232336D02*
X314497Y232114D01*
G01X313535Y231308D02*
X313534D01*
G01X313806Y231172D02*
X313535Y231308D01*
G01X314050Y232336D02*
X314051D01*
G01X313806Y231172D02*
X313535Y231308D01*
G01X304768Y214623D02*
X304769D01*
G01X304835Y213369D02*
X305282Y213593D01*
G01X304166Y214321D02*
X304768Y214623D01*
G01X305282Y213593D02*
X305283D01*
G01X304835Y213369D02*
X305282Y213593D01*
G01X302755Y211125D02*
G02X304166Y214321I4325J0D01*
G01X303905Y211124D02*
G02X304835Y213369I3175J0D01*
G01X302755Y208621D02*
Y211125D01*
G01X303905Y208800D02*
Y211124D01*
G01X309238Y188208D02*
X302755Y208621D01*
G01X304433Y207138D02*
X303905Y208800D01*
G01X305729Y203058D02*
X305275Y204488D01*
G01X307024Y198979D02*
X306570Y200409D01*
G01X310297Y188674D02*
X307866Y196330D01*
G01X305282Y213593D02*
X305283D01*
G01X304166Y214321D02*
X304768Y214623D01*
G01X304835Y213369D02*
X305282Y213593D01*
G01X304768Y214623D02*
X304769D01*
G01X304166Y214321D02*
X304768Y214623D01*
G01X303905Y211124D02*
G02X304835Y213369I3175J0D01*
G01X302755Y211125D02*
G02X304166Y214321I4325J0D01*
G01X303905Y208800D02*
Y211124D01*
G01X302755Y208621D02*
Y211125D01*
G01X304433Y207138D02*
X303905Y208800D01*
G01X309238Y188208D02*
X302755Y208621D01*
G01X305729Y203058D02*
X305275Y204488D01*
G01X309238Y188208D02*
X302755Y208621D01*
G01X307024Y198979D02*
X306570Y200409D01*
G01X309238Y188208D02*
X302755Y208621D01*
G01X310297Y188674D02*
X307866Y196330D01*
G01X309238Y188208D02*
X302755Y208621D01*
G01X297794Y231307D02*
X297793D01*
G01X298755Y232113D02*
X298308Y232337D01*
G01X298062Y231173D02*
X297794Y231307D01*
G01X298308Y232337D02*
X298307D01*
G01X298755Y232113D02*
X298308Y232337D01*
G01X299114Y228468D02*
G03X298062Y231173I-4004J0D01*
G01X300265Y228468D02*
G03X298755Y232113I-5155J0D01*
G01X298749Y222912D02*
G03X299114Y228468I-42098J5556D01*
G01X299890Y222761D02*
G03X300265Y228468I-43239J5707D01*
G01X298740Y218291D02*
Y222837D01*
G01X299890Y218318D02*
Y222761D01*
G01X298366Y216745D02*
G03X298740Y218291I-2706J1473D01*
G01X299376Y216195D02*
G03X299890Y218318I-3716J2023D01*
G01X297989Y216052D02*
X298366Y216745D01*
G01X298999Y215502D02*
X299376Y216195D01*
G01X297903Y215938D02*
G03X297989Y216052I-352J355D01*
G01X298716Y215124D02*
G03X298999Y215502I-1166J1168D01*
G01X296389Y214425D02*
X297903Y215938D01*
G01X297203Y213611D02*
X298716Y215124D01*
G01X295333Y211874D02*
G02X296389Y214425I3609J0D01*
G01X296484Y211874D02*
G02X297203Y213611I2458J0D01*
G01X295333Y207922D02*
Y211874D01*
G01X296483Y208192D02*
Y211875D01*
G01X295473Y207640D02*
X295333Y207922D01*
G01X296503Y208152D02*
X296483Y208192D01*
G01X308244Y184588D02*
X296503Y208152D01*
G01X296142Y206297D02*
X295473Y207640D01*
G01X296503Y208152D02*
X296483Y208192D01*
G01X308244Y184588D02*
X296503Y208152D01*
G01X298050Y202466D02*
X297381Y203809D01*
G01X308244Y184588D02*
X296503Y208152D01*
G01X307234Y184028D02*
X299290Y199978D01*
G01X308244Y184588D02*
X296503Y208152D01*
G01X282511Y199674D02*
X284034Y194956D01*
G01X285100Y195400D02*
X281000Y208100D01*
G01X281196Y203747D02*
X281657Y202320D01*
G01X285100Y195400D02*
X281000Y208100D01*
G01X279881Y207820D02*
X280342Y206393D01*
G01X285100Y195400D02*
X281000Y208100D01*
G01X279868Y207896D02*
X279881Y207820D01*
G01X281000Y208100D02*
X280738Y209551D01*
G01X279588Y209448D02*
X279868Y207896D01*
G01X281000Y208100D02*
X280738Y209551D01*
G01X279588Y211874D02*
Y209448D01*
G01X280738Y209551D02*
Y211873D01*
G01X280644Y214425D02*
G03X279588Y211874I2553J-2551D01*
G01X280739D02*
G02X281458Y213611I2458J0D01*
G01X281401Y215182D02*
X280644Y214425D01*
G01X281458Y213611D02*
X282971Y215124D01*
G01X282158Y215938D02*
X281401Y215182D01*
G01X281458Y213611D02*
X282971Y215124D01*
G01X282244Y216052D02*
G02X282158Y215938I-438J241D01*
G01X282971Y215124D02*
G03X283254Y215502I-1166J1168D01*
G01X282621Y216745D02*
X282244Y216052D01*
G01X283254Y215502D02*
X283631Y216195D01*
G01X282995Y218291D02*
G02X282621Y216745I-3080J-73D01*
G01X283631Y216195D02*
G03X284145Y218318I-3716J2023D01*
G01X282995Y222837D02*
Y218291D01*
G01X284145Y218318D02*
Y222761D01*
G01X283369Y228468D02*
G02X283004Y222912I-42463J0D01*
G01X284145Y222761D02*
G03X284520Y228468I-43239J5707D01*
G01X282317Y231173D02*
G02X283369Y228468I-2952J-2705D01*
G01X284520D02*
G03X283010Y232113I-5155J0D01*
G01X282049Y231307D02*
X282317Y231173D01*
G01X282563Y232337D02*
X282562D01*
G01X283010Y232113D02*
X282563Y232337D01*
G01X282048Y231307D02*
X282049D01*
G01X283010Y232113D02*
X282563Y232337D01*
G01X298308D02*
X298307D01*
G01X298062Y231173D02*
X297794Y231307D01*
G01X298755Y232113D02*
X298308Y232337D01*
G01X297794Y231307D02*
X297793D01*
G01X298062Y231173D02*
X297794Y231307D01*
G01X300265Y228468D02*
G03X298755Y232113I-5155J0D01*
G01X299114Y228468D02*
G03X298062Y231173I-4004J0D01*
G01X299890Y222761D02*
G03X300265Y228468I-43239J5707D01*
G01X298749Y222912D02*
G03X299114Y228468I-42098J5556D01*
G01X299890Y218318D02*
Y222761D01*
G01X298740Y218291D02*
Y222837D01*
G01X299376Y216195D02*
G03X299890Y218318I-3716J2023D01*
G01X298366Y216745D02*
G03X298740Y218291I-2706J1473D01*
G01X298999Y215502D02*
X299376Y216195D01*
G01X297989Y216052D02*
X298366Y216745D01*
G01X298716Y215124D02*
G03X298999Y215502I-1166J1168D01*
G01X297903Y215938D02*
G03X297989Y216052I-352J355D01*
G01X297203Y213611D02*
X298716Y215124D01*
G01X296389Y214425D02*
X297903Y215938D01*
G01X296484Y211874D02*
G02X297203Y213611I2458J0D01*
G01X295333Y211874D02*
G02X296389Y214425I3609J0D01*
G01X296483Y208192D02*
Y211875D01*
G01X295333Y207922D02*
Y211874D01*
G01X296503Y208152D02*
X296483Y208192D01*
G01X295473Y207640D02*
X295333Y207922D01*
G01X296142Y206297D02*
X295473Y207640D01*
G01X308244Y184588D02*
X296503Y208152D01*
G01X295473Y207640D02*
X295333Y207922D01*
G01X296142Y206297D02*
X295473Y207640D01*
G01X298050Y202466D02*
X297381Y203809D01*
G01X307234Y184028D02*
X299290Y199978D01*
G01X282563Y232337D02*
X282562D01*
G01X282049Y231307D02*
X282317Y231173D01*
G01X283010Y232113D02*
X282563Y232337D01*
G01X282049Y231307D02*
X282317Y231173D01*
G01X282048Y231307D02*
X282049D01*
G01X284520Y228468D02*
G03X283010Y232113I-5155J0D01*
G01X282317Y231173D02*
G02X283369Y228468I-2952J-2705D01*
G01X284145Y222761D02*
G03X284520Y228468I-43239J5707D01*
G01X283369D02*
G02X283004Y222912I-42463J0D01*
G01X284145Y218318D02*
Y222761D01*
G01X282995Y222837D02*
Y218291D01*
G01X283631Y216195D02*
G03X284145Y218318I-3716J2023D01*
G01X282995Y218291D02*
G02X282621Y216745I-3080J-73D01*
G01X283254Y215502D02*
X283631Y216195D01*
G01X282621Y216745D02*
X282244Y216052D01*
G01X282971Y215124D02*
G03X283254Y215502I-1166J1168D01*
G01X282244Y216052D02*
G02X282158Y215938I-438J241D01*
G01X281458Y213611D02*
X282971Y215124D01*
G01X281401Y215182D02*
X280644Y214425D01*
G01X282158Y215938D02*
X281401Y215182D01*
G01X280739Y211874D02*
G02X281458Y213611I2458J0D01*
G01X280644Y214425D02*
G03X279588Y211874I2553J-2551D01*
G01X280738Y209551D02*
Y211873D01*
G01X279588Y211874D02*
Y209448D01*
G01X281000Y208100D02*
X280738Y209551D01*
G01X279868Y207896D02*
X279881Y207820D01*
G01X279588Y209448D02*
X279868Y207896D01*
G01X285100Y195400D02*
X281000Y208100D01*
G01X282511Y199674D02*
X284034Y194956D01*
G01X281196Y203747D02*
X281657Y202320D01*
G01X279881Y207820D02*
X280342Y206393D01*
G01X289020Y214621D02*
X289021D01*
G01X289536Y213593D02*
X289267Y213459D01*
G01X288574Y214399D02*
X289013Y214618D01*
G01X289536Y213593D02*
X289267Y213459D01*
G01X289537Y213593D02*
X289536D01*
G01X287204Y211056D02*
G02X288574Y214399I4677J36D01*
G01X289267Y213459D02*
G03X288354Y211091I2614J-2368D01*
G01X287330Y208823D02*
X287204Y211056D01*
G01X288354Y211091D02*
X288473Y208992D01*
G01X292005Y189405D02*
X287330Y208823D01*
G01X291478Y196509D02*
X293123Y189675D01*
G01X290476Y200670D02*
X290827Y199211D01*
G01X289475Y204831D02*
X289826Y203373D01*
G01X288473Y208992D02*
X288824Y207534D01*
G01X292367Y188700D02*
X292137Y189083D01*
G01X274168Y203893D02*
X273489Y205231D01*
G01X276105Y200077D02*
X275426Y201414D01*
G01X278041Y196260D02*
X277363Y197598D01*
G01X271454Y206731D02*
X272492Y204653D01*
G01X273489Y205231D02*
X272604Y207003D01*
G01X271454Y211092D02*
Y206731D01*
G01X272604Y207003D02*
Y211091D01*
G01X272824Y214399D02*
G03X271454Y211092I3307J-3307D01*
G01X272604Y211091D02*
G02X273517Y213459I3527J0D01*
G01X273263Y214618D02*
X272824Y214399D01*
G01X273786Y213593D02*
X273787D01*
G01X273776Y213588D02*
X273786Y213593D01*
G01X273517Y213459D02*
X273776Y213588D01*
G01X273271Y214621D02*
X273270D01*
G01X273517Y213459D02*
X273776Y213588D01*
G01X292367Y188700D02*
X292137Y189083D01*
G01X291478Y196509D02*
X293123Y189675D01*
G01X292005Y189405D02*
X287330Y208823D01*
G01X290476Y200670D02*
X290827Y199211D01*
G01X292005Y189405D02*
X287330Y208823D01*
G01X289475Y204831D02*
X289826Y203373D01*
G01X292005Y189405D02*
X287330Y208823D01*
G01X288473Y208992D02*
X288824Y207534D01*
G01X292005Y189405D02*
X287330Y208823D01*
G01X288354Y211091D02*
X288473Y208992D01*
G01X287330Y208823D02*
X287204Y211056D01*
G01X289267Y213459D02*
G03X288354Y211091I2614J-2368D01*
G01X287204Y211056D02*
G02X288574Y214399I4677J36D01*
G01X289536Y213593D02*
X289267Y213459D01*
G01X289020Y214621D02*
X289021D01*
G01X288574Y214399D02*
X289013Y214618D01*
G01X289537Y213593D02*
X289536D01*
G01X288574Y214399D02*
X289013Y214618D01*
G01X273786Y213593D02*
X273787D01*
G01X273263Y214618D02*
X272824Y214399D01*
G01X273776Y213588D02*
X273786Y213593D01*
G01X273263Y214618D02*
X272824Y214399D01*
G01X273517Y213459D02*
X273776Y213588D01*
G01X273263Y214618D02*
X272824Y214399D01*
G01X273271Y214621D02*
X273270D01*
G01X272604Y211091D02*
G02X273517Y213459I3527J0D01*
G01X272824Y214399D02*
G03X271454Y211092I3307J-3307D01*
G01X272604Y207003D02*
Y211091D01*
G01X271454Y211092D02*
Y206731D01*
G01X273489Y205231D02*
X272604Y207003D01*
G01X271454Y206731D02*
X272492Y204653D01*
G01X274168Y203893D02*
X273489Y205231D01*
G01X276105Y200077D02*
X275426Y201414D01*
G01X278041Y196260D02*
X277363Y197598D01*
G01X268770Y228468D02*
G03X267260Y232113I-5155J0D01*
G01X267254Y222912D02*
G03X267619Y228468I-42098J5556D01*
G01X268395Y222761D02*
G03X268770Y228468I-43239J5707D01*
G01X267245Y218303D02*
Y222837D01*
G01X268395Y218317D02*
Y222761D01*
G01X267881Y216195D02*
G03X268395Y218317I-3716J2023D01*
G01X268770Y228468D02*
G03X267260Y232113I-5155J0D01*
G01X268395Y222761D02*
G03X268770Y228468I-43239J5707D01*
G01X267254Y222912D02*
G03X267619Y228468I-42098J5556D01*
G01X268395Y218317D02*
Y222761D01*
G01X267245Y218303D02*
Y222837D01*
G01X267881Y216195D02*
G03X268395Y218317I-3716J2023D01*
G01X269879Y184448D02*
X269671Y184781D01*
G01X270126Y184052D02*
X269879Y184448D01*
G01X271713Y180610D02*
X270126Y184052D01*
G01X272800Y181000D02*
X271141Y184600D01*
G01X269879Y184448D02*
X269671Y184781D01*
G01X270126Y184052D02*
X269879Y184448D01*
G01X272800Y181000D02*
X271141Y184600D01*
G01X271713Y180610D02*
X270126Y184052D01*
G01X405434Y-71378D02*
Y-42638D01*
G01X403466Y-73346D02*
X405434Y-71378D01*
G01X369846Y8397D02*
X367646Y10694D01*
G01X368399Y11572D02*
X370734Y9134D01*
G01X394305Y-25788D02*
X369846Y8397D01*
G01X370734Y9134D02*
X395300Y-25200D01*
G01X397671Y-32817D02*
X394305Y-25788D01*
G01X395300Y-25200D02*
X399282Y-33518D01*
G01X398101Y-33716D02*
X397671Y-32817D01*
G01X395300Y-25200D02*
X399282Y-33518D01*
G01X395300Y-25200D02*
X399282Y-33518D01*
G01X397671Y-32817D02*
X394305Y-25788D01*
G01X398101Y-33716D02*
X397671Y-32817D01*
G01X370734Y9134D02*
X395300Y-25200D01*
G01X394305Y-25788D02*
X369846Y8397D01*
G01X368399Y11572D02*
X370734Y9134D01*
G01X369846Y8397D02*
X367646Y10694D01*
G01X367300Y5100D02*
X364105Y8189D01*
G01X368178Y5851D02*
X364842Y9077D01*
G01X378649Y-11050D02*
X367300Y5100D01*
G01X391021Y-26652D02*
X368178Y5851D01*
G01X389999Y-27200D02*
X378649Y-11050D01*
G01X391021Y-26652D02*
X368178Y5851D01*
G01X392562Y-33756D02*
X390001Y-27203D01*
G01X393633Y-33337D02*
X391021Y-26652D01*
G01X392849Y-35289D02*
X392562Y-33756D01*
G01X393999Y-35182D02*
X393692Y-33544D01*
G01X392925Y-37890D02*
G03X392849Y-35292I-8005J1066D01*
G01X394066Y-38041D02*
G03X394000Y-35182I-9146J1219D01*
G01X392916Y-40666D02*
G02X392925Y-37890I10852J1353D01*
G01X394066Y-40592D02*
G02Y-38041I9702J1275D01*
G01X392916Y-42329D02*
Y-40666D01*
G01X394066Y-43826D02*
Y-40592D01*
G01X368178Y5851D02*
X364842Y9077D01*
G01X367300Y5100D02*
X364105Y8189D01*
G01X391021Y-26652D02*
X368178Y5851D01*
G01X378649Y-11050D02*
X367300Y5100D01*
G01X389999Y-27200D02*
X378649Y-11050D01*
G01X393633Y-33337D02*
X391021Y-26652D01*
G01X392562Y-33756D02*
X390001Y-27203D01*
G01X393999Y-35182D02*
X393692Y-33544D01*
G01X392849Y-35289D02*
X392562Y-33756D01*
G01X394066Y-38041D02*
G03X394000Y-35182I-9146J1219D01*
G01X392925Y-37890D02*
G03X392849Y-35292I-8005J1066D01*
G01X394066Y-40592D02*
G02Y-38041I9702J1275D01*
G01X392916Y-40666D02*
G02X392925Y-37890I10852J1353D01*
G01X394066Y-43826D02*
Y-40592D01*
G01X392916Y-42329D02*
Y-40666D01*
G01X364710Y964D02*
X357738Y8176D01*
G01X365600Y1700D02*
X358488Y9055D01*
G01X385709Y-28890D02*
X364710Y964D01*
G01X386700Y-28300D02*
X365600Y1700D01*
G01X387993Y-33888D02*
X385709Y-28890D01*
G01X389162Y-33679D02*
X386711Y-28315D01*
G01X387932Y-34703D02*
X387993Y-33888D01*
G01X389085Y-34718D02*
X389162Y-33679D01*
G01X377732Y-33115D02*
Y-34703D01*
G01X378882Y-34668D02*
Y-32921D01*
G01X376888Y-30681D02*
X377732Y-33115D01*
G01X378882Y-32921D02*
X377923Y-30152D01*
G01X361005Y-7999D02*
X376888Y-30681D01*
G01X377830Y-30020D02*
X361831Y-7173D01*
G01X377923Y-30152D02*
X377830Y-30020D01*
G01X365600Y1700D02*
X358488Y9055D01*
G01X364710Y964D02*
X357738Y8176D01*
G01X386700Y-28300D02*
X365600Y1700D01*
G01X385709Y-28890D02*
X364710Y964D01*
G01X389162Y-33679D02*
X386711Y-28315D01*
G01X387993Y-33888D02*
X385709Y-28890D01*
G01X389085Y-34718D02*
X389162Y-33679D01*
G01X387932Y-34703D02*
X387993Y-33888D01*
G01X377830Y-30020D02*
X361831Y-7173D01*
G01X361005Y-7999D02*
X376888Y-30681D01*
G01X377923Y-30152D02*
X377830Y-30020D01*
G01X361005Y-7999D02*
X376888Y-30681D01*
G01X378882Y-32921D02*
X377923Y-30152D01*
G01X376888Y-30681D02*
X377732Y-33115D01*
G01X378882Y-34668D02*
Y-32921D01*
G01X377732Y-33115D02*
Y-34703D01*
G01X381628Y-30039D02*
X364216Y-5168D01*
G01X365042Y-4342D02*
X382711Y-29579D01*
G01X382648Y-35292D02*
X381628Y-30039D01*
G01X382711Y-29579D02*
X383777Y-35073D01*
G01X382725Y-37890D02*
G03X382648Y-35292I-8006J1063D01*
G01X383777Y-35073D02*
G02X383866Y-38041I-9057J-1757D01*
G01X382716Y-40666D02*
G02X382725Y-37890I10852J1353D01*
G01X383866Y-38041D02*
G03Y-40592I9702J-1276D01*
G01X382716Y-42329D02*
Y-40666D01*
G01X383866Y-40592D02*
Y-43826D01*
G01X382712Y-43974D02*
Y-43800D01*
G01X383866Y-40592D02*
Y-43826D01*
G01X372511Y-41927D02*
Y-44688D01*
G01X373661Y-44653D02*
Y-41950D01*
G01X372525Y-40741D02*
G02X372511Y-41927I-21718J-337D01*
G01X373661Y-41950D02*
G03X373675Y-40724I-22854J874D01*
G01X372525Y-37890D02*
G03Y-40741I10843J-1426D01*
G01X373666Y-40592D02*
G02Y-38041I9702J1275D01*
G01X372578Y-36312D02*
G02X372525Y-37890I-8059J-519D01*
G01X373666Y-38040D02*
G03X373727Y-36238I-9147J1212D01*
G01X372457Y-35344D02*
G02X372578Y-36312I-7938J-1484D01*
G01X373727Y-36238D02*
G03X373588Y-35132I-9207J-595D01*
G01X373666Y-38040D02*
G03X373727Y-36238I-9147J1212D01*
G01X371794Y-31805D02*
X372457Y-35344D01*
G01X373588Y-35132D02*
X372879Y-31349D01*
G01X364071Y-20776D02*
X371794Y-31805D01*
G01X372879Y-31349D02*
X357174Y-8918D01*
G01X356348Y-9744D02*
X364072Y-20776D01*
G01X372879Y-31349D02*
X357174Y-8918D01*
G01X383866Y-40592D02*
Y-43826D01*
G01X382716Y-42329D02*
Y-40666D01*
G01X382712Y-43974D02*
Y-43800D01*
G01X383866Y-38041D02*
G03Y-40592I9702J-1276D01*
G01X382716Y-40666D02*
G02X382725Y-37890I10852J1353D01*
G01X383777Y-35073D02*
G02X383866Y-38041I-9057J-1757D01*
G01X382725Y-37890D02*
G03X382648Y-35292I-8006J1063D01*
G01X382711Y-29579D02*
X383777Y-35073D01*
G01X382648Y-35292D02*
X381628Y-30039D01*
G01X365042Y-4342D02*
X382711Y-29579D01*
G01X381628Y-30039D02*
X364216Y-5168D01*
G01X372879Y-31349D02*
X357174Y-8918D01*
G01X364071Y-20776D02*
X371794Y-31805D01*
G01X356348Y-9744D02*
X364072Y-20776D01*
G01X373588Y-35132D02*
X372879Y-31349D01*
G01X371794Y-31805D02*
X372457Y-35344D01*
G01X373727Y-36238D02*
G03X373588Y-35132I-9207J-595D01*
G01X372457Y-35344D02*
G02X372578Y-36312I-7938J-1484D01*
G01X373666Y-38040D02*
G03X373727Y-36238I-9147J1212D01*
G01X372578Y-36312D02*
G02X372525Y-37890I-8059J-519D01*
G01X372457Y-35344D02*
G02X372578Y-36312I-7938J-1484D01*
G01X373666Y-40592D02*
G02Y-38041I9702J1275D01*
G01X372525Y-37890D02*
G03Y-40741I10843J-1426D01*
G01X373661Y-41950D02*
G03X373675Y-40724I-22854J874D01*
G01X372525Y-40741D02*
G02X372511Y-41927I-21718J-337D01*
G01X373661Y-44653D02*
Y-41950D01*
G01X372511Y-41927D02*
Y-44688D01*
G01X367189Y-32832D02*
X352248Y-11499D01*
G01X368132Y-32173D02*
X353190Y-10839D01*
G01X367532Y-34775D02*
X367189Y-32833D01*
G01X368682Y-34668D02*
X368322Y-32633D01*
G01X368132Y-32173D02*
X353190Y-10839D01*
G01X367189Y-32832D02*
X352248Y-11499D01*
G01X368682Y-34668D02*
X368322Y-32633D01*
G01X367532Y-34775D02*
X367189Y-32833D01*
G01X361801Y-33000D02*
X347606Y-12728D01*
G01X362792Y-32410D02*
X348432Y-11902D01*
G01X361802Y-33002D02*
X361801Y-33000D01*
G01X362901Y-32628D02*
X362792Y-32410D01*
G01X361921Y-33615D02*
X361802Y-33002D01*
G01X363051Y-33396D02*
X362901Y-32628D01*
G01X363376Y-35073D02*
X363051Y-33396D01*
G01X362247Y-35292D02*
X361921Y-33615D01*
G01X363051Y-33396D02*
X362901Y-32628D01*
G01X363376Y-35073D02*
X363051Y-33396D01*
G01X362325Y-37890D02*
G03X362247Y-35292I-8006J1060D01*
G01X363466Y-38040D02*
G03X363376Y-35073I-9147J1207D01*
G01X362325Y-40741D02*
G02Y-37890I10843J1426D01*
G01X363466Y-40592D02*
G02Y-38041I9702J1275D01*
G01X362405Y-43820D02*
G03X362325Y-40741I-14702J1159D01*
G01X363552Y-43910D02*
G03X363466Y-40592I-15849J1249D01*
G01X362311Y-44688D02*
G03X362405Y-43820I-14609J2021D01*
G01X363552Y-43910D02*
G03X363466Y-40592I-15849J1249D01*
G01X362792Y-32410D02*
X348432Y-11902D01*
G01X361801Y-33000D02*
X347606Y-12728D01*
G01X362901Y-32628D02*
X362792Y-32410D01*
G01X361802Y-33002D02*
X361801Y-33000D01*
G01X363051Y-33396D02*
X362901Y-32628D01*
G01X361921Y-33615D02*
X361802Y-33002D01*
G01X362247Y-35292D02*
X361921Y-33615D01*
G01X363376Y-35073D02*
X363051Y-33396D01*
G01X361921Y-33615D02*
X361802Y-33002D01*
G01X362247Y-35292D02*
X361921Y-33615D01*
G01X363466Y-38040D02*
G03X363376Y-35073I-9147J1207D01*
G01X362325Y-37890D02*
G03X362247Y-35292I-8006J1060D01*
G01X363466Y-40592D02*
G02Y-38041I9702J1275D01*
G01X362325Y-40741D02*
G02Y-37890I10843J1426D01*
G01X363552Y-43910D02*
G03X363466Y-40592I-15849J1249D01*
G01X362405Y-43820D02*
G03X362325Y-40741I-14702J1159D01*
G01X362311Y-44688D02*
G03X362405Y-43820I-14609J2021D01*
G01X357205Y-33105D02*
X357313Y-33716D01*
G01X358294Y-32654D02*
X358462Y-33604D01*
G01X358294Y-32654D02*
X358462Y-33604D01*
G01X357205Y-33105D02*
X357313Y-33716D01*
G01X352182Y-37813D02*
Y-33445D01*
G01X353332Y-37884D02*
Y-33082D01*
G01X351931Y-39851D02*
X352182Y-37813D01*
G01X353088Y-39873D02*
X353332Y-37884D01*
G01X352111Y-41972D02*
X351931Y-39851D01*
G01X353261Y-41923D02*
X353088Y-39873D01*
G01X352111Y-44688D02*
Y-41972D01*
G01X353261Y-44653D02*
Y-41923D01*
G01X353332Y-37884D02*
Y-33082D01*
G01X352182Y-37813D02*
Y-33445D01*
G01X353088Y-39873D02*
X353332Y-37884D01*
G01X351931Y-39851D02*
X352182Y-37813D01*
G01X353261Y-41923D02*
X353088Y-39873D01*
G01X352111Y-41972D02*
X351931Y-39851D01*
G01X353261Y-44653D02*
Y-41923D01*
G01X352111Y-44688D02*
Y-41972D01*
G01X347945Y-32686D02*
X348265Y-34504D01*
G01X347945Y-32686D02*
X348265Y-34504D01*
G01X406221Y-41850D02*
X439883D01*
G01X406221D02*
G03X405434Y-42638I1J-788D01*
G01X428505Y563228D02*
X426536Y565196D01*
G01X442639Y-73346D02*
X538111D01*
G01X440670Y-71378D02*
X442639Y-73346D01*
G01X440670Y-42638D02*
Y-71378D01*
G01X447700Y-23700D02*
X524080D01*
G01X447120Y-25100D02*
X523500D01*
G01X443000Y-19000D02*
X447700Y-23700D01*
G01X441600Y-19580D02*
X447120Y-25100D01*
G01X443000Y7600D02*
Y-19000D01*
G01X441600Y8180D02*
Y-19580D01*
G01X467400Y32000D02*
X443000Y7600D01*
G01X466000Y32580D02*
X441600Y8180D01*
G01X447120Y-25100D02*
X523500D01*
G01X447700Y-23700D02*
X524080D01*
G01X441600Y-19580D02*
X447120Y-25100D01*
G01X443000Y-19000D02*
X447700Y-23700D01*
G01X441600Y8180D02*
Y-19580D01*
G01X443000Y7600D02*
Y-19000D01*
G01X466000Y32580D02*
X441600Y8180D01*
G01X467400Y32000D02*
X443000Y7600D01*
G01X440670Y-42638D02*
G03X439883Y-41850I-787J1D01*
G01X467400Y49000D02*
Y32000D01*
G01X466000Y34080D02*
Y32580D01*
G01Y38860D02*
Y37360D01*
G01Y43640D02*
Y42140D01*
G01Y48420D02*
Y46920D01*
G01X465187Y51213D02*
X467400Y49000D01*
G01X464607Y49813D02*
X466000Y48420D01*
G01X462567Y51213D02*
X465187D01*
G01X462568Y49813D02*
X464607D01*
G01X466000Y34080D02*
Y32580D01*
G01X467400Y49000D02*
Y32000D01*
G01X466000Y38860D02*
Y37360D01*
G01X467400Y49000D02*
Y32000D01*
G01X466000Y43640D02*
Y42140D01*
G01X467400Y49000D02*
Y32000D01*
G01X466000Y48420D02*
Y46920D01*
G01X467400Y49000D02*
Y32000D01*
G01X464607Y49813D02*
X466000Y48420D01*
G01X465187Y51213D02*
X467400Y49000D01*
G01X462568Y49813D02*
X464607D01*
G01X462567Y51213D02*
X465187D01*
G01X428504Y544723D02*
Y563227D01*
G01Y544723D02*
G03X437953I4724J0D01*
G01Y563227D02*
Y544723D01*
G01X428505Y544724D02*
Y563228D01*
G01Y544724D02*
G03X437954I4725J0D01*
G01Y563228D02*
Y544724D01*
G01X439922Y565196D02*
X437954Y563228D01*
G01X540828Y565196D02*
X439922D01*
G01X547954Y-73346D02*
X622403D01*
G01X547954D02*
Y-7874D01*
G01X540080Y-71378D02*
Y-3937D01*
G01X538111Y-73346D02*
X540080Y-71378D01*
G01X528715Y-28335D02*
Y-37115D01*
G01X527315Y-28915D02*
Y-37285D01*
G01X524080Y-23700D02*
X528715Y-28335D01*
G01X523500Y-25100D02*
X527315Y-28915D01*
G01D02*
Y-37285D01*
G01X528715Y-28335D02*
Y-37115D01*
G01X523500Y-25100D02*
X527315Y-28915D01*
G01X524080Y-23700D02*
X528715Y-28335D01*
G01X558662Y9505D02*
Y155374D01*
G01X557509Y6721D02*
G03X558662Y9505I-2784J2784D01*
G01X551942Y1153D02*
X557509Y6721D01*
G01X549158Y0D02*
G03X551942Y1153I0J3937D01*
G01X544017Y0D02*
X549158D01*
G01X544017D02*
G03X540080Y-3937I0J-3937D01*
G01X547954Y-7874D02*
X549158D01*
G01Y0D02*
G03X551942Y1153I0J3937D01*
G01X549158Y-7875D02*
G03X557510Y-4415I0J11811D01*
G01X551942Y1153D02*
X557509Y6721D01*
G01X557510Y-4414D02*
X563077Y1154D01*
G01X557509Y6721D02*
G03X558662Y9505I-2784J2784D01*
G01X563077Y1153D02*
G03X566536Y9507I-8352J8351D01*
G01X558662Y9505D02*
Y155374D01*
G01X566536Y9505D02*
Y18655D01*
G01D02*
G03X558662I-3937J-1D01*
G01Y49363D02*
G03X566536I3937J0D01*
G01D02*
Y151437D01*
G01X562599Y159311D02*
X611812D01*
G01X562599D02*
G03X558662Y155374I0J-3937D01*
G01X562599Y159311D02*
G03X558662Y155374I0J-3937D01*
G01X562599Y159311D02*
X611812D01*
G01X566536Y151437D02*
X574076D01*
G01D02*
G03Y159311I0J3937D01*
G01X564353Y249862D02*
G03Y241988I0J-3937D01*
G01X521844D02*
G03Y249862I0J3937D01*
G01X542796Y495787D02*
Y563228D01*
G01Y495787D02*
G03X546733Y491850I3937J0D01*
G01X606244D02*
X546733D01*
G01X606244D02*
X546733D01*
G01X542796Y495787D02*
G03X546733Y491850I3937J0D01*
G01X550670Y499724D02*
Y563622D01*
G01X570124Y491850D02*
G03Y499724I0J3937D01*
G01D02*
X550670D01*
G01Y565196D02*
X622403D01*
G01X542796Y563228D02*
X540828Y565196D01*
G01X550670Y563622D02*
Y565196D01*
G01X622403Y-73346D02*
G03X637403Y-58346I0J15000D01*
G01Y253799D02*
Y-58346D01*
G01X615749Y163248D02*
Y228546D01*
G01X611812Y159311D02*
G03X615749Y163248I0J3937D01*
G01X611812Y159311D02*
G03X615749Y163248I0J3937D01*
G01X611812Y151437D02*
G03X623623Y163248I0J11811D01*
G01X615749D02*
Y228546D01*
G01X623623Y163248D02*
Y228546D01*
G01X604785Y159311D02*
G03Y151437I0J-3937D01*
G01D02*
X611812D01*
G01X615749Y253799D02*
Y482345D01*
G01X611812Y249862D02*
G03X615749Y253799I0J3937D01*
G01X605091Y240835D02*
G03X602307Y241988I-2784J-2784D01*
G01X614596Y231330D02*
X605091Y240835D01*
G01X615749Y228546D02*
G03X614596Y231330I-3937J0D01*
G01X615749Y228546D02*
G03X614596Y231330I-3937J0D01*
G01D02*
X605091Y240835D01*
G01D02*
G03X602307Y241988I-2784J-2784D01*
G01X611812Y249862D02*
G03X615749Y253799I0J3937D01*
G01D02*
Y482345D01*
G01X623623Y253799D02*
Y274659D01*
G01X637403Y253799D02*
Y482345D01*
G01X623623Y228546D02*
Y253799D01*
G01Y274659D02*
G03X615749I-3937J0D01*
G01Y305368D02*
G03X623623I3937J0D01*
G01D02*
Y410289D01*
G01D02*
G03X615749I-3937J0D01*
G01X609028Y490697D02*
G03X606244Y491850I-2784J-2784D01*
G01X614596Y485129D02*
X609028Y490697D01*
G01X615749Y482345D02*
G03X614596Y485129I-3937J0D01*
G01X615749Y482345D02*
G03X614596Y485129I-3937J0D01*
G01X623623Y482345D02*
G03X620164Y490697I-11811J1D01*
G01X614596Y485129D02*
X609028Y490697D01*
G01X620164D02*
X614596Y496265D01*
G01X609028Y490697D02*
G03X606244Y491850I-2784J-2784D01*
G01X614596Y496265D02*
G03X606244Y499724I-8351J-8352D01*
G01D02*
X600833D01*
G01X637403Y482345D02*
Y550196D01*
G01X600833Y499724D02*
G03Y491850I0J-3937D01*
G01X615749Y440998D02*
G03X623623I3937J0D01*
G01D02*
Y482345D01*
G01X637403Y550196D02*
G03X622403Y565196I-15000J0D01*
G54D12*
G01X-15353Y-106096D02*
Y-123596D01*
G01X-20375Y-106096D02*
X-10331D01*
G01X-1565Y-123596D02*
Y-106096D01*
G01Y-114554D02*
X-473Y-113096D01*
X619Y-112221D01*
X2365Y-111930D01*
X3675Y-112221D01*
X5204Y-113388D01*
X5859Y-115138D01*
Y-123596D01*
G01X19647Y-111930D02*
Y-123596D01*
G01Y-107263D02*
X19210Y-106971D01*
Y-106388D01*
X19647Y-106096D01*
X20084Y-106388D01*
Y-106971D01*
X19647Y-107263D01*
G01X33872Y-121555D02*
X34964Y-122721D01*
X36492Y-123596D01*
X37802D01*
X39112Y-123013D01*
X39985Y-122138D01*
X40422Y-120972D01*
X40204Y-119221D01*
X39330Y-118346D01*
X35400Y-116596D01*
X34527Y-114554D01*
X34964Y-113096D01*
X35837Y-112221D01*
X37147Y-111930D01*
X38457Y-112221D01*
X39767Y-113096D01*
G01X69090Y-127971D02*
X70619Y-129138D01*
X72365Y-129429D01*
X73893Y-129138D01*
X75204Y-127680D01*
X76077Y-125638D01*
Y-111930D01*
G01Y-114263D02*
X75204Y-113096D01*
X73893Y-112221D01*
X72365Y-111930D01*
X70619Y-112513D01*
X69527Y-113679D01*
X68653Y-115721D01*
X68217Y-117763D01*
X68435Y-119513D01*
X69309Y-121555D01*
X70619Y-123013D01*
X72365Y-123596D01*
X73675Y-123304D01*
X75204Y-122138D01*
X76077Y-120972D01*
G01X86372Y-115721D02*
X93359D01*
X92704Y-113679D01*
X91612Y-112513D01*
X90084Y-111930D01*
X88555Y-112221D01*
X87245Y-113096D01*
X86372Y-115138D01*
X85935Y-116888D01*
Y-118638D01*
X86372Y-120388D01*
X87464Y-122138D01*
X88774Y-123304D01*
X90302Y-123596D01*
X91830Y-123013D01*
X93359Y-121263D01*
G01X104090Y-123596D02*
Y-111930D01*
G01Y-114263D02*
X105182Y-113096D01*
X106274Y-112221D01*
X107802Y-111930D01*
X108893Y-112221D01*
X110204Y-113096D01*
G01X120717Y-123596D02*
Y-106096D01*
G01Y-114846D02*
X121809Y-113096D01*
X123119Y-112221D01*
X124429Y-111930D01*
X126393Y-112513D01*
X127704Y-113679D01*
X128577Y-115721D01*
Y-118054D01*
X128140Y-120388D01*
X127267Y-122138D01*
X125739Y-123304D01*
X124429Y-123596D01*
X123119Y-123304D01*
X121809Y-122430D01*
X120717Y-120972D01*
G01X138872Y-115721D02*
X145859D01*
X145204Y-113679D01*
X144112Y-112513D01*
X142584Y-111930D01*
X141055Y-112221D01*
X139745Y-113096D01*
X138872Y-115138D01*
X138435Y-116888D01*
Y-118638D01*
X138872Y-120388D01*
X139964Y-122138D01*
X141274Y-123304D01*
X142802Y-123596D01*
X144330Y-123013D01*
X145859Y-121263D01*
G01X156590Y-123596D02*
Y-111930D01*
G01Y-114263D02*
X157682Y-113096D01*
X158774Y-112221D01*
X160302Y-111930D01*
X161393Y-112221D01*
X162704Y-113096D01*
G01X194647Y-111930D02*
Y-123596D01*
G01Y-107263D02*
X194210Y-106971D01*
Y-106388D01*
X194647Y-106096D01*
X195084Y-106388D01*
Y-106971D01*
X194647Y-107263D01*
G01X208872Y-121555D02*
X209964Y-122721D01*
X211492Y-123596D01*
X212802D01*
X214112Y-123013D01*
X214985Y-122138D01*
X215422Y-120972D01*
X215204Y-119221D01*
X214330Y-118346D01*
X210400Y-116596D01*
X209527Y-114554D01*
X209964Y-113096D01*
X210837Y-112221D01*
X212147Y-111930D01*
X213457Y-112221D01*
X214767Y-113096D01*
G01X243653Y-127971D02*
X245182Y-129138D01*
X246492Y-129429D01*
X248239Y-128846D01*
X249549Y-127388D01*
X250204Y-124762D01*
Y-111930D01*
G01Y-107263D02*
X249767Y-106971D01*
Y-106388D01*
X250204Y-106096D01*
X250640Y-106388D01*
Y-106971D01*
X250204Y-107263D01*
G01X260935Y-111930D02*
Y-120096D01*
X261809Y-122138D01*
X263119Y-123304D01*
X264647Y-123596D01*
X266175Y-123304D01*
X267485Y-122138D01*
X268359Y-120096D01*
G01Y-123596D02*
Y-111930D01*
G01X278872Y-121555D02*
X279964Y-122721D01*
X281492Y-123596D01*
X282802D01*
X284112Y-123013D01*
X284985Y-122138D01*
X285422Y-120972D01*
X285204Y-119221D01*
X284330Y-118346D01*
X280400Y-116596D01*
X279527Y-114554D01*
X279964Y-113096D01*
X280837Y-112221D01*
X282147Y-111930D01*
X283457Y-112221D01*
X284767Y-113096D01*
G01X299647Y-106096D02*
Y-123596D01*
G01X296590Y-111930D02*
X302704D01*
G01X333337Y-123596D02*
Y-108721D01*
X333774Y-107263D01*
X334647Y-106388D01*
X335957Y-106096D01*
X337267Y-106679D01*
X337922Y-108138D01*
G01X335302Y-113096D02*
X330935D01*
G01X352147Y-123596D02*
X350837Y-123304D01*
X349527Y-122138D01*
X348653Y-120096D01*
X348217Y-117763D01*
X348653Y-115429D01*
X349527Y-113388D01*
X350837Y-112221D01*
X352147Y-111930D01*
X353457Y-112221D01*
X354767Y-113388D01*
X355640Y-115429D01*
X355859Y-117763D01*
X355640Y-120096D01*
X354767Y-122138D01*
X353457Y-123304D01*
X352147Y-123596D01*
G01X366590D02*
Y-111930D01*
G01Y-114263D02*
X367682Y-113096D01*
X368774Y-112221D01*
X370302Y-111930D01*
X371393Y-112221D01*
X372704Y-113096D01*
G01X400062Y-128846D02*
X401372Y-129429D01*
X403119Y-128846D01*
X404210Y-127680D01*
X405084Y-126221D01*
X406393Y-121555D01*
X409232Y-111930D01*
G01X402245D02*
X406393Y-121555D01*
G01X422147Y-123596D02*
X420837Y-123304D01*
X419527Y-122138D01*
X418653Y-120096D01*
X418217Y-117763D01*
X418653Y-115429D01*
X419527Y-113388D01*
X420837Y-112221D01*
X422147Y-111930D01*
X423457Y-112221D01*
X424767Y-113388D01*
X425640Y-115429D01*
X425859Y-117763D01*
X425640Y-120096D01*
X424767Y-122138D01*
X423457Y-123304D01*
X422147Y-123596D01*
G01X435935Y-111930D02*
Y-120096D01*
X436809Y-122138D01*
X438119Y-123304D01*
X439647Y-123596D01*
X441175Y-123304D01*
X442485Y-122138D01*
X443359Y-120096D01*
G01Y-123596D02*
Y-111930D01*
G01X454090Y-123596D02*
Y-111930D01*
G01Y-114263D02*
X455182Y-113096D01*
X456274Y-112221D01*
X457802Y-111930D01*
X458893Y-112221D01*
X460204Y-113096D01*
G01X489090Y-123596D02*
Y-111930D01*
G01Y-114263D02*
X490182Y-113096D01*
X491274Y-112221D01*
X492802Y-111930D01*
X493893Y-112221D01*
X495204Y-113096D01*
G01X506372Y-115721D02*
X513359D01*
X512704Y-113679D01*
X511612Y-112513D01*
X510084Y-111930D01*
X508555Y-112221D01*
X507245Y-113096D01*
X506372Y-115138D01*
X505935Y-116888D01*
Y-118638D01*
X506372Y-120388D01*
X507464Y-122138D01*
X508774Y-123304D01*
X510302Y-123596D01*
X511830Y-123013D01*
X513359Y-121263D01*
G01X525837Y-123596D02*
Y-108721D01*
X526274Y-107263D01*
X527147Y-106388D01*
X528457Y-106096D01*
X529767Y-106679D01*
X530422Y-108138D01*
G01X527802Y-113096D02*
X523435D01*
G01X541372Y-115721D02*
X548359D01*
X547704Y-113679D01*
X546612Y-112513D01*
X545084Y-111930D01*
X543555Y-112221D01*
X542245Y-113096D01*
X541372Y-115138D01*
X540935Y-116888D01*
Y-118638D01*
X541372Y-120388D01*
X542464Y-122138D01*
X543774Y-123304D01*
X545302Y-123596D01*
X546830Y-123013D01*
X548359Y-121263D01*
G01X559090Y-123596D02*
Y-111930D01*
G01Y-114263D02*
X560182Y-113096D01*
X561274Y-112221D01*
X562802Y-111930D01*
X563893Y-112221D01*
X565204Y-113096D01*
G01X576372Y-115721D02*
X583359D01*
X582704Y-113679D01*
X581612Y-112513D01*
X580084Y-111930D01*
X578555Y-112221D01*
X577245Y-113096D01*
X576372Y-115138D01*
X575935Y-116888D01*
Y-118638D01*
X576372Y-120388D01*
X577464Y-122138D01*
X578774Y-123304D01*
X580302Y-123596D01*
X581830Y-123013D01*
X583359Y-121263D01*
G01X593435Y-123596D02*
Y-111930D01*
G01Y-114846D02*
X594309Y-113388D01*
X595619Y-112221D01*
X597365Y-111930D01*
X598893Y-112221D01*
X600204Y-113388D01*
X600859Y-115429D01*
Y-123596D01*
G01X618140Y-113388D02*
X616612Y-112221D01*
X615302Y-111930D01*
X613555Y-112513D01*
X612245Y-113679D01*
X611372Y-115721D01*
X611153Y-117763D01*
X611372Y-119805D01*
X612245Y-121555D01*
X613555Y-123013D01*
X615302Y-123596D01*
X616830Y-123013D01*
X618140Y-121846D01*
G01X628872Y-115721D02*
X635859D01*
X635204Y-113679D01*
X634112Y-112513D01*
X632584Y-111930D01*
X631055Y-112221D01*
X629745Y-113096D01*
X628872Y-115138D01*
X628435Y-116888D01*
Y-118638D01*
X628872Y-120388D01*
X629964Y-122138D01*
X631274Y-123304D01*
X632802Y-123596D01*
X634330Y-123013D01*
X635859Y-121263D01*
G01X667147Y-106096D02*
Y-123596D01*
G01X664090Y-111930D02*
X670204D01*
G01X684647Y-123596D02*
X683337Y-123304D01*
X682027Y-122138D01*
X681153Y-120096D01*
X680717Y-117763D01*
X681153Y-115429D01*
X682027Y-113388D01*
X683337Y-112221D01*
X684647Y-111930D01*
X685957Y-112221D01*
X687267Y-113388D01*
X688140Y-115429D01*
X688359Y-117763D01*
X688140Y-120096D01*
X687267Y-122138D01*
X685957Y-123304D01*
X684647Y-123596D01*
G01X718337D02*
Y-108721D01*
X718774Y-107263D01*
X719647Y-106388D01*
X720957Y-106096D01*
X722267Y-106679D01*
X722922Y-108138D01*
G01X720302Y-113096D02*
X715935D01*
G01X737147Y-111930D02*
Y-123596D01*
G01Y-107263D02*
X736710Y-106971D01*
Y-106388D01*
X737147Y-106096D01*
X737584Y-106388D01*
Y-106971D01*
X737147Y-107263D01*
G01X750935Y-123596D02*
Y-111930D01*
G01Y-114846D02*
X751809Y-113388D01*
X753119Y-112221D01*
X754865Y-111930D01*
X756393Y-112221D01*
X757704Y-113388D01*
X758359Y-115429D01*
Y-123596D01*
G01X776077Y-106096D02*
Y-123596D01*
G01Y-120972D02*
X775204Y-122430D01*
X773893Y-123304D01*
X772365Y-123596D01*
X770619Y-123013D01*
X769309Y-121555D01*
X768435Y-119805D01*
X768217Y-117763D01*
X768435Y-115721D01*
X769309Y-113971D01*
X770619Y-112513D01*
X772365Y-111930D01*
X773893Y-112221D01*
X774985Y-112805D01*
X776077Y-113971D01*
G01X807147Y-106096D02*
Y-123596D01*
G01X804090Y-111930D02*
X810204D01*
G01X820935Y-123596D02*
Y-106096D01*
G01Y-114554D02*
X822027Y-113096D01*
X823119Y-112221D01*
X824865Y-111930D01*
X826175Y-112221D01*
X827704Y-113388D01*
X828359Y-115138D01*
Y-123596D01*
G01X838872Y-115721D02*
X845859D01*
X845204Y-113679D01*
X844112Y-112513D01*
X842584Y-111930D01*
X841055Y-112221D01*
X839745Y-113096D01*
X838872Y-115138D01*
X838435Y-116888D01*
Y-118638D01*
X838872Y-120388D01*
X839964Y-122138D01*
X841274Y-123304D01*
X842802Y-123596D01*
X844330Y-123013D01*
X845859Y-121263D01*
G01X872344Y-123596D02*
Y-106096D01*
X876710D01*
X878457Y-106971D01*
X879767Y-108138D01*
X880859Y-109887D01*
X881732Y-111930D01*
X881950Y-114846D01*
X881732Y-117763D01*
X880859Y-119805D01*
X879767Y-121555D01*
X878457Y-122721D01*
X876710Y-123596D01*
X872344D01*
G01X890280D02*
Y-106096D01*
X895520D01*
X897267Y-106971D01*
X898577Y-109013D01*
X899014Y-111346D01*
X898577Y-113679D01*
X897485Y-115429D01*
X895520Y-116305D01*
X890280D01*
G01X929647Y-111930D02*
Y-123596D01*
G01Y-107263D02*
X929210Y-106971D01*
Y-106388D01*
X929647Y-106096D01*
X930084Y-106388D01*
Y-106971D01*
X929647Y-107263D01*
G01X940597Y-123596D02*
Y-111930D01*
G01Y-115138D02*
X941252Y-113679D01*
X942344Y-112513D01*
X943872Y-111930D01*
X945400Y-112513D01*
X946492Y-113679D01*
X947147Y-115138D01*
Y-123596D01*
G01Y-115138D02*
X947802Y-113679D01*
X948893Y-112513D01*
X950422Y-111930D01*
X951950Y-112513D01*
X953042Y-113679D01*
X953697Y-115429D01*
Y-123596D01*
G01X960717Y-129429D02*
Y-111930D01*
G01Y-114554D02*
X961809Y-113096D01*
X962900Y-112221D01*
X964647Y-111930D01*
X966175Y-112221D01*
X967704Y-113679D01*
X968359Y-115721D01*
X968577Y-117763D01*
X968359Y-119805D01*
X967704Y-121846D01*
X966393Y-123013D01*
X964647Y-123596D01*
X963119Y-123304D01*
X961590Y-122430D01*
X960717Y-121263D01*
G01X978872Y-115721D02*
X985859D01*
X985204Y-113679D01*
X984112Y-112513D01*
X982584Y-111930D01*
X981055Y-112221D01*
X979745Y-113096D01*
X978872Y-115138D01*
X978435Y-116888D01*
Y-118638D01*
X978872Y-120388D01*
X979964Y-122138D01*
X981274Y-123304D01*
X982802Y-123596D01*
X984330Y-123013D01*
X985859Y-121263D01*
G01X1003577Y-106096D02*
Y-123596D01*
G01Y-120972D02*
X1002704Y-122430D01*
X1001393Y-123304D01*
X999865Y-123596D01*
X998119Y-123013D01*
X996809Y-121555D01*
X995935Y-119805D01*
X995717Y-117763D01*
X995935Y-115721D01*
X996809Y-113971D01*
X998119Y-112513D01*
X999865Y-111930D01*
X1001393Y-112221D01*
X1002485Y-112805D01*
X1003577Y-113971D01*
G01X1021077Y-123596D02*
Y-111930D01*
G01Y-113971D02*
X1020204Y-112805D01*
X1018893Y-112221D01*
X1017365Y-111930D01*
X1015837Y-112513D01*
X1014527Y-113679D01*
X1013653Y-115429D01*
X1013217Y-117763D01*
X1013653Y-120096D01*
X1014527Y-121846D01*
X1015837Y-123013D01*
X1017365Y-123596D01*
X1018893Y-123304D01*
X1020204Y-122430D01*
X1021077Y-121263D01*
G01X1030935Y-123596D02*
Y-111930D01*
G01Y-114846D02*
X1031809Y-113388D01*
X1033119Y-112221D01*
X1034865Y-111930D01*
X1036393Y-112221D01*
X1037704Y-113388D01*
X1038359Y-115429D01*
Y-123596D01*
G01X1055640Y-113388D02*
X1054112Y-112221D01*
X1052802Y-111930D01*
X1051055Y-112513D01*
X1049745Y-113679D01*
X1048872Y-115721D01*
X1048653Y-117763D01*
X1048872Y-119805D01*
X1049745Y-121555D01*
X1051055Y-123013D01*
X1052802Y-123596D01*
X1054330Y-123013D01*
X1055640Y-121846D01*
G01X1066372Y-115721D02*
X1073359D01*
X1072704Y-113679D01*
X1071612Y-112513D01*
X1070084Y-111930D01*
X1068555Y-112221D01*
X1067245Y-113096D01*
X1066372Y-115138D01*
X1065935Y-116888D01*
Y-118638D01*
X1066372Y-120388D01*
X1067464Y-122138D01*
X1068774Y-123304D01*
X1070302Y-123596D01*
X1071830Y-123013D01*
X1073359Y-121263D01*
G01X1104647Y-106096D02*
Y-123596D01*
G01X1101590Y-111930D02*
X1107704D01*
G01X1119090Y-123596D02*
Y-111930D01*
G01Y-114263D02*
X1120182Y-113096D01*
X1121274Y-112221D01*
X1122802Y-111930D01*
X1123893Y-112221D01*
X1125204Y-113096D01*
G01X1143577Y-123596D02*
Y-111930D01*
G01Y-113971D02*
X1142704Y-112805D01*
X1141393Y-112221D01*
X1139865Y-111930D01*
X1138337Y-112513D01*
X1137027Y-113679D01*
X1136153Y-115429D01*
X1135717Y-117763D01*
X1136153Y-120096D01*
X1137027Y-121846D01*
X1138337Y-123013D01*
X1139865Y-123596D01*
X1141393Y-123304D01*
X1142704Y-122430D01*
X1143577Y-121263D01*
G01X1160640Y-113388D02*
X1159112Y-112221D01*
X1157802Y-111930D01*
X1156055Y-112513D01*
X1154745Y-113679D01*
X1153872Y-115721D01*
X1153653Y-117763D01*
X1153872Y-119805D01*
X1154745Y-121555D01*
X1156055Y-123013D01*
X1157802Y-123596D01*
X1159330Y-123013D01*
X1160640Y-121846D01*
G01X1171372Y-115721D02*
X1178359D01*
X1177704Y-113679D01*
X1176612Y-112513D01*
X1175084Y-111930D01*
X1173555Y-112221D01*
X1172245Y-113096D01*
X1171372Y-115138D01*
X1170935Y-116888D01*
Y-118638D01*
X1171372Y-120388D01*
X1172464Y-122138D01*
X1173774Y-123304D01*
X1175302Y-123596D01*
X1176830Y-123013D01*
X1178359Y-121263D01*
G01X1188872Y-121555D02*
X1189964Y-122721D01*
X1191492Y-123596D01*
X1192802D01*
X1194112Y-123013D01*
X1194985Y-122138D01*
X1195422Y-120972D01*
X1195204Y-119221D01*
X1194330Y-118346D01*
X1190400Y-116596D01*
X1189527Y-114554D01*
X1189964Y-113096D01*
X1190837Y-112221D01*
X1192147Y-111930D01*
X1193457Y-112221D01*
X1194767Y-113096D01*
G01X1227147Y-111930D02*
Y-123596D01*
G01Y-107263D02*
X1226710Y-106971D01*
Y-106388D01*
X1227147Y-106096D01*
X1227584Y-106388D01*
Y-106971D01*
X1227147Y-107263D01*
G01X1240935Y-123596D02*
Y-111930D01*
G01Y-114846D02*
X1241809Y-113388D01*
X1243119Y-112221D01*
X1244865Y-111930D01*
X1246393Y-112221D01*
X1247704Y-113388D01*
X1248359Y-115429D01*
Y-123596D01*
G01X1279647D02*
Y-106096D01*
G01X1301077Y-123596D02*
Y-111930D01*
G01Y-113971D02*
X1300204Y-112805D01*
X1298893Y-112221D01*
X1297365Y-111930D01*
X1295837Y-112513D01*
X1294527Y-113679D01*
X1293653Y-115429D01*
X1293217Y-117763D01*
X1293653Y-120096D01*
X1294527Y-121846D01*
X1295837Y-123013D01*
X1297365Y-123596D01*
X1298893Y-123304D01*
X1300204Y-122430D01*
X1301077Y-121263D01*
G01X1310062Y-128846D02*
X1311372Y-129429D01*
X1313119Y-128846D01*
X1314210Y-127680D01*
X1315084Y-126221D01*
X1316393Y-121555D01*
X1319232Y-111930D01*
G01X1312245D02*
X1316393Y-121555D01*
G01X1328872Y-115721D02*
X1335859D01*
X1335204Y-113679D01*
X1334112Y-112513D01*
X1332584Y-111930D01*
X1331055Y-112221D01*
X1329745Y-113096D01*
X1328872Y-115138D01*
X1328435Y-116888D01*
Y-118638D01*
X1328872Y-120388D01*
X1329964Y-122138D01*
X1331274Y-123304D01*
X1332802Y-123596D01*
X1334330Y-123013D01*
X1335859Y-121263D01*
G01X1346590Y-123596D02*
Y-111930D01*
G01Y-114263D02*
X1347682Y-113096D01*
X1348774Y-112221D01*
X1350302Y-111930D01*
X1351393Y-112221D01*
X1352704Y-113096D01*
G01X1380280Y-106096D02*
Y-123596D01*
X1389014D01*
G01X1397344Y-120096D02*
X1398653Y-122138D01*
X1400400Y-123304D01*
X1402365Y-123596D01*
X1404112Y-123304D01*
X1405859Y-121846D01*
X1406950Y-120096D01*
X1407169Y-118346D01*
X1406732Y-116305D01*
X1405204Y-114846D01*
X1403675Y-114263D01*
X1401710D01*
G01X1403675D02*
X1404985Y-113388D01*
X1406077Y-111930D01*
X1406514Y-110180D01*
X1406077Y-108429D01*
X1404985Y-106971D01*
X1403020Y-106096D01*
X1401055Y-106388D01*
X1399090Y-107555D01*
G01X1419647Y-124179D02*
X1419210Y-123888D01*
Y-123304D01*
X1419647Y-123013D01*
X1420084Y-123304D01*
Y-123888D01*
X1419647Y-124179D01*
G01X748903Y471246D02*
X750431Y471538D01*
X752178Y472412D01*
X753270Y473870D01*
X753706Y475913D01*
X753270Y477954D01*
X751960Y479704D01*
X749995Y480579D01*
X747811D01*
X746501Y481163D01*
X745409Y482621D01*
X744973Y484662D01*
X745628Y486704D01*
X747156Y488163D01*
X748903Y488746D01*
X750649Y488163D01*
X752178Y486704D01*
X752833Y484662D01*
X752396Y482621D01*
X751305Y481163D01*
X749995Y480579D01*
X747811D01*
X745846Y479704D01*
X744536Y477954D01*
X744100Y475913D01*
X744536Y473870D01*
X745628Y472412D01*
X747375Y471538D01*
X748903Y471246D01*
G01X761600Y473870D02*
X762909Y472412D01*
X764438Y471538D01*
X766403Y471246D01*
X768368Y471829D01*
X769896Y472996D01*
X770988Y475037D01*
X771206Y477371D01*
X770770Y479704D01*
X769678Y481163D01*
X768149Y482329D01*
X766621Y482621D01*
X765093Y482329D01*
X763128Y481163D01*
X763783Y488746D01*
X769678D01*
G01X783903Y470663D02*
X783466Y470954D01*
Y471538D01*
X783903Y471829D01*
X784340Y471538D01*
Y470954D01*
X783903Y470663D01*
G01X801403Y488746D02*
X799656Y488163D01*
X798346Y486704D01*
X797473Y484955D01*
X796818Y482621D01*
X796600Y479996D01*
X796818Y477371D01*
X797473Y475037D01*
X798346Y473287D01*
X799656Y471829D01*
X801403Y471246D01*
X803149Y471829D01*
X804460Y473287D01*
X805333Y475037D01*
X805988Y477371D01*
X806206Y479996D01*
X805988Y482621D01*
X805333Y484955D01*
X804460Y486704D01*
X803149Y488163D01*
X801403Y488746D01*
G01X745191Y438637D02*
X746720Y437179D01*
X748466Y436596D01*
X750213Y437179D01*
X751741Y438929D01*
X752833Y441554D01*
X753270Y444179D01*
Y447387D01*
X752833Y450012D01*
X751741Y452346D01*
X750431Y453513D01*
X748903Y454096D01*
X747156Y453513D01*
X745846Y452346D01*
X744973Y450596D01*
X744536Y448262D01*
X744973Y446221D01*
X746065Y444179D01*
X747375Y443012D01*
X748903Y442721D01*
X750649Y443304D01*
X751960Y444763D01*
X753270Y447387D01*
G01X766403Y454096D02*
X764656Y453513D01*
X763346Y452054D01*
X762473Y450305D01*
X761818Y447971D01*
X761600Y445346D01*
X761818Y442721D01*
X762473Y440387D01*
X763346Y438637D01*
X764656Y437179D01*
X766403Y436596D01*
X768149Y437179D01*
X769460Y438637D01*
X770333Y440387D01*
X770988Y442721D01*
X771206Y445346D01*
X770988Y447971D01*
X770333Y450305D01*
X769460Y452054D01*
X768149Y453513D01*
X766403Y454096D01*
G01X783903Y436013D02*
X783466Y436304D01*
Y436888D01*
X783903Y437179D01*
X784340Y436888D01*
Y436304D01*
X783903Y436013D01*
G01X801403Y454096D02*
X799656Y453513D01*
X798346Y452054D01*
X797473Y450305D01*
X796818Y447971D01*
X796600Y445346D01*
X796818Y442721D01*
X797473Y440387D01*
X798346Y438637D01*
X799656Y437179D01*
X801403Y436596D01*
X803149Y437179D01*
X804460Y438637D01*
X805333Y440387D01*
X805988Y442721D01*
X806206Y445346D01*
X805988Y447971D01*
X805333Y450305D01*
X804460Y452054D01*
X803149Y453513D01*
X801403Y454096D01*
G01X689400Y540546D02*
Y558046D01*
X693766D01*
X695513Y557171D01*
X696823Y556004D01*
X697915Y554255D01*
X698788Y552212D01*
X699006Y549296D01*
X698788Y546379D01*
X697915Y544337D01*
X696823Y542587D01*
X695513Y541421D01*
X693766Y540546D01*
X689400D01*
G01X707336D02*
Y558046D01*
X712576D01*
X714323Y557171D01*
X715633Y555129D01*
X716070Y552796D01*
X715633Y550463D01*
X714541Y548713D01*
X712576Y547837D01*
X707336D01*
G01X744083Y558046D02*
X749323D01*
G01X746703D02*
Y540546D01*
G01X744083D02*
X749323D01*
G01X758526D02*
Y558046D01*
X764203Y543463D01*
X769880Y558046D01*
Y540546D01*
G01X777336D02*
Y558046D01*
X782576D01*
X784323Y557171D01*
X785633Y555129D01*
X786070Y552796D01*
X785633Y550463D01*
X784541Y548713D01*
X782576Y547837D01*
X777336D01*
G01X803570Y540546D02*
X794836D01*
Y558046D01*
X803570D01*
G01X800076Y549588D02*
X794836D01*
G01X811900Y540546D02*
Y558046D01*
X816266D01*
X818013Y557171D01*
X819323Y556004D01*
X820415Y554255D01*
X821288Y552212D01*
X821506Y549296D01*
X821288Y546379D01*
X820415Y544337D01*
X819323Y542587D01*
X818013Y541421D01*
X816266Y540546D01*
X811900D01*
G01X828744D02*
X834203Y558046D01*
X839662Y540546D01*
G01X837696Y546671D02*
X830709D01*
G01X846681Y540546D02*
Y558046D01*
X856725Y540546D01*
Y558046D01*
G01X874006Y556587D02*
X872696Y557463D01*
X871168Y558046D01*
X869421D01*
X867456Y557171D01*
X865928Y555713D01*
X864836Y553962D01*
X863963Y551046D01*
X863744Y548421D01*
X864181Y545796D01*
X864836Y544046D01*
X866146Y542296D01*
X867675Y541129D01*
X869203Y540546D01*
X870731D01*
X872260Y541129D01*
X873570Y542004D01*
X874662Y543170D01*
G01X891070Y540546D02*
X882336D01*
Y558046D01*
X891070D01*
G01X887576Y549588D02*
X882336D01*
G01X921703Y558046D02*
Y540546D01*
G01X916681Y558046D02*
X926725D01*
G01X933744Y540546D02*
X939203Y558046D01*
X944662Y540546D01*
G01X942696Y546671D02*
X935709D01*
G01X958449Y549879D02*
X959323Y550754D01*
X959978Y552212D01*
X960415Y554255D01*
X959978Y556004D01*
X959105Y557171D01*
X957576Y558046D01*
X951681D01*
Y540546D01*
X958886D01*
X960415Y541712D01*
X961288Y543463D01*
X961725Y545504D01*
X961288Y547546D01*
X959978Y549296D01*
X958449Y549879D01*
X951681D01*
G01X969836Y558046D02*
Y540546D01*
X978570D01*
G01X996070D02*
X987336D01*
Y558046D01*
X996070D01*
G01X992576Y549588D02*
X987336D01*
G01X1009203Y539963D02*
X1008766Y540254D01*
Y540838D01*
X1009203Y541129D01*
X1009640Y540838D01*
Y540254D01*
X1009203Y539963D01*
G01Y547837D02*
X1008766Y548129D01*
Y548713D01*
X1009203Y549004D01*
X1009640Y548713D01*
Y548129D01*
X1009203Y547837D01*
G01X1039836Y558046D02*
Y540546D01*
X1048570D01*
G01X1056900Y544046D02*
X1058209Y542004D01*
X1059956Y540838D01*
X1061921Y540546D01*
X1063668Y540838D01*
X1065415Y542296D01*
X1066506Y544046D01*
X1066725Y545796D01*
X1066288Y547837D01*
X1064760Y549296D01*
X1063231Y549879D01*
X1061266D01*
G01X1063231D02*
X1064541Y550754D01*
X1065633Y552212D01*
X1066070Y553962D01*
X1065633Y555713D01*
X1064541Y557171D01*
X1062576Y558046D01*
X1060611Y557754D01*
X1058646Y556587D01*
G01X711283Y523396D02*
X716523D01*
G01X713903D02*
Y505896D01*
G01X711283D02*
X716523D01*
G01X725726D02*
Y523396D01*
X731403Y508813D01*
X737080Y523396D01*
Y505896D01*
G01X744536D02*
Y523396D01*
X749776D01*
X751523Y522521D01*
X752833Y520479D01*
X753270Y518146D01*
X752833Y515813D01*
X751741Y514063D01*
X749776Y513187D01*
X744536D01*
G01X765311Y500063D02*
X763128Y502979D01*
X762036Y505896D01*
Y517562D01*
X763128Y520479D01*
X765311Y523396D01*
G01X783903Y505896D02*
X782156Y506188D01*
X780628Y507354D01*
X779318Y509104D01*
X778444Y511146D01*
X778008Y513479D01*
Y515813D01*
X778444Y518146D01*
X779318Y520188D01*
X780628Y521937D01*
X782156Y523104D01*
X783903Y523396D01*
X785649Y523104D01*
X787178Y521937D01*
X788488Y520188D01*
X789362Y518146D01*
X789798Y515813D01*
Y513479D01*
X789362Y511146D01*
X788488Y509104D01*
X787178Y507354D01*
X785649Y506188D01*
X783903Y505896D01*
G01X797691D02*
Y523396D01*
G01Y514938D02*
X798783Y516396D01*
X799875Y517271D01*
X801621Y517562D01*
X802931Y517271D01*
X804460Y516104D01*
X805115Y514354D01*
Y505896D01*
G01X812353D02*
Y517562D01*
G01Y514354D02*
X813008Y515813D01*
X814100Y516979D01*
X815628Y517562D01*
X817156Y516979D01*
X818248Y515813D01*
X818903Y514354D01*
Y505896D01*
G01Y514354D02*
X819558Y515813D01*
X820649Y516979D01*
X822178Y517562D01*
X823706Y516979D01*
X824798Y515813D01*
X825453Y514063D01*
Y505896D01*
G01X837495Y500063D02*
X839678Y502979D01*
X840770Y505896D01*
Y517562D01*
X839678Y520479D01*
X837495Y523396D01*
G01X891103D02*
X894159Y505896D01*
X897653Y523396D01*
X901146Y505896D01*
X904203Y523396D01*
G01X912533D02*
X917773D01*
G01X915153D02*
Y505896D01*
G01X912533D02*
X917773D01*
G01X927850D02*
Y523396D01*
X932216D01*
X933963Y522521D01*
X935273Y521354D01*
X936365Y519605D01*
X937238Y517562D01*
X937456Y514646D01*
X937238Y511729D01*
X936365Y509687D01*
X935273Y507937D01*
X933963Y506771D01*
X932216Y505896D01*
X927850D01*
G01X950153Y523396D02*
Y505896D01*
G01X945131Y523396D02*
X955175D01*
G01X963068Y505896D02*
Y523396D01*
G01X972238D02*
Y505896D01*
G01Y514646D02*
X963068D01*
G01X984061Y500063D02*
X981878Y502979D01*
X980786Y505896D01*
Y517562D01*
X981878Y520479D01*
X984061Y523396D01*
G01X996103Y505896D02*
Y517562D01*
G01Y514354D02*
X996758Y515813D01*
X997850Y516979D01*
X999378Y517562D01*
X1000906Y516979D01*
X1001998Y515813D01*
X1002653Y514354D01*
Y505896D01*
G01Y514354D02*
X1003308Y515813D01*
X1004399Y516979D01*
X1005928Y517562D01*
X1007456Y516979D01*
X1008548Y515813D01*
X1009203Y514063D01*
Y505896D01*
G01X1020153Y517562D02*
Y505896D01*
G01Y522229D02*
X1019716Y522521D01*
Y523104D01*
X1020153Y523396D01*
X1020590Y523104D01*
Y522521D01*
X1020153Y522229D01*
G01X1037653Y505896D02*
Y523396D01*
G01X1051878Y507937D02*
X1052970Y506771D01*
X1054498Y505896D01*
X1055808D01*
X1057118Y506479D01*
X1057991Y507354D01*
X1058428Y508520D01*
X1058210Y510271D01*
X1057336Y511146D01*
X1053406Y512896D01*
X1052533Y514938D01*
X1052970Y516396D01*
X1053843Y517271D01*
X1055153Y517562D01*
X1056463Y517271D01*
X1057773Y516396D01*
G01X1073745Y500063D02*
X1075928Y502979D01*
X1077020Y505896D01*
Y517562D01*
X1075928Y520479D01*
X1073745Y523396D01*
G01X927850Y473870D02*
X929159Y472412D01*
X930688Y471538D01*
X932653Y471246D01*
X934618Y471829D01*
X936146Y472996D01*
X937238Y475037D01*
X937456Y477371D01*
X937020Y479704D01*
X935928Y481163D01*
X934399Y482329D01*
X932871Y482621D01*
X931343Y482329D01*
X929378Y481163D01*
X930033Y488746D01*
X935928D01*
G01X950153Y470663D02*
X949716Y470954D01*
Y471538D01*
X950153Y471829D01*
X950590Y471538D01*
Y470954D01*
X950153Y470663D01*
G01X967653Y488746D02*
X965906Y488163D01*
X964596Y486704D01*
X963723Y484955D01*
X963068Y482621D01*
X962850Y479996D01*
X963068Y477371D01*
X963723Y475037D01*
X964596Y473287D01*
X965906Y471829D01*
X967653Y471246D01*
X969399Y471829D01*
X970710Y473287D01*
X971583Y475037D01*
X972238Y477371D01*
X972456Y479996D01*
X972238Y482621D01*
X971583Y484955D01*
X970710Y486704D01*
X969399Y488163D01*
X967653Y488746D01*
G01X981223Y470663D02*
X989083Y488746D01*
G01X998505Y478537D02*
X1000033Y480579D01*
X1001343Y481746D01*
X1003090Y482329D01*
X1004618Y481746D01*
X1005710Y480579D01*
X1006583Y478829D01*
X1006801Y476788D01*
X1006583Y475037D01*
X1005710Y473287D01*
X1004399Y471829D01*
X1002871Y471246D01*
X1001125Y471829D01*
X999596Y473579D01*
X998723Y476204D01*
X998505Y479121D01*
X998941Y482912D01*
X999596Y484955D01*
X1000688Y486996D01*
X1002216Y488454D01*
X1003745Y488746D01*
X1005273Y488163D01*
X1006365Y486704D01*
G01X1020153Y470663D02*
X1019716Y470954D01*
Y471538D01*
X1020153Y471829D01*
X1020590Y471538D01*
Y470954D01*
X1020153Y470663D01*
G01X1032850Y473870D02*
X1034159Y472412D01*
X1035688Y471538D01*
X1037653Y471246D01*
X1039618Y471829D01*
X1041146Y472996D01*
X1042238Y475037D01*
X1042456Y477371D01*
X1042020Y479704D01*
X1040928Y481163D01*
X1039399Y482329D01*
X1037871Y482621D01*
X1036343Y482329D01*
X1034378Y481163D01*
X1035033Y488746D01*
X1040928D01*
G01X927850Y439220D02*
X929159Y437762D01*
X930688Y436888D01*
X932653Y436596D01*
X934618Y437179D01*
X936146Y438346D01*
X937238Y440387D01*
X937456Y442721D01*
X937020Y445054D01*
X935928Y446513D01*
X934399Y447679D01*
X932871Y447971D01*
X931343Y447679D01*
X929378Y446513D01*
X930033Y454096D01*
X935928D01*
G01X950153Y436013D02*
X949716Y436304D01*
Y436888D01*
X950153Y437179D01*
X950590Y436888D01*
Y436304D01*
X950153Y436013D01*
G01X967653Y454096D02*
X965906Y453513D01*
X964596Y452054D01*
X963723Y450305D01*
X963068Y447971D01*
X962850Y445346D01*
X963068Y442721D01*
X963723Y440387D01*
X964596Y438637D01*
X965906Y437179D01*
X967653Y436596D01*
X969399Y437179D01*
X970710Y438637D01*
X971583Y440387D01*
X972238Y442721D01*
X972456Y445346D01*
X972238Y447971D01*
X971583Y450305D01*
X970710Y452054D01*
X969399Y453513D01*
X967653Y454096D01*
G01X981223Y436013D02*
X989083Y454096D01*
G01X998941Y438637D02*
X1000470Y437179D01*
X1002216Y436596D01*
X1003963Y437179D01*
X1005491Y438929D01*
X1006583Y441554D01*
X1007020Y444179D01*
Y447387D01*
X1006583Y450012D01*
X1005491Y452346D01*
X1004181Y453513D01*
X1002653Y454096D01*
X1000906Y453513D01*
X999596Y452346D01*
X998723Y450596D01*
X998286Y448262D01*
X998723Y446221D01*
X999815Y444179D01*
X1001125Y443012D01*
X1002653Y442721D01*
X1004399Y443304D01*
X1005710Y444763D01*
X1007020Y447387D01*
G01X1020153Y436013D02*
X1019716Y436304D01*
Y436888D01*
X1020153Y437179D01*
X1020590Y436888D01*
Y436304D01*
X1020153Y436013D01*
G01X1037653Y454096D02*
X1035906Y453513D01*
X1034596Y452054D01*
X1033723Y450305D01*
X1033068Y447971D01*
X1032850Y445346D01*
X1033068Y442721D01*
X1033723Y440387D01*
X1034596Y438637D01*
X1035906Y437179D01*
X1037653Y436596D01*
X1039399Y437179D01*
X1040710Y438637D01*
X1041583Y440387D01*
X1042238Y442721D01*
X1042456Y445346D01*
X1042238Y447971D01*
X1041583Y450305D01*
X1040710Y452054D01*
X1039399Y453513D01*
X1037653Y454096D01*
G01X1146600Y471246D02*
Y488746D01*
X1150966D01*
X1152713Y487871D01*
X1154023Y486704D01*
X1155115Y484955D01*
X1155988Y482912D01*
X1156206Y479996D01*
X1155988Y477079D01*
X1155115Y475037D01*
X1154023Y473287D01*
X1152713Y472121D01*
X1150966Y471246D01*
X1146600D01*
G01X1164536D02*
Y488746D01*
X1169776D01*
X1171523Y487871D01*
X1172833Y485829D01*
X1173270Y483496D01*
X1172833Y481163D01*
X1171741Y479413D01*
X1169776Y478537D01*
X1164536D01*
G01X1146600Y436596D02*
Y454096D01*
X1150966D01*
X1152713Y453221D01*
X1154023Y452054D01*
X1155115Y450305D01*
X1155988Y448262D01*
X1156206Y445346D01*
X1155988Y442429D01*
X1155115Y440387D01*
X1154023Y438637D01*
X1152713Y437471D01*
X1150966Y436596D01*
X1146600D01*
G01X1164536D02*
Y454096D01*
X1169776D01*
X1171523Y453221D01*
X1172833Y451179D01*
X1173270Y448846D01*
X1172833Y446513D01*
X1171741Y444763D01*
X1169776Y443887D01*
X1164536D01*
G01X1133903Y523396D02*
Y505896D01*
G01X1128881Y523396D02*
X1138925D01*
G01X1151403Y505896D02*
Y513771D01*
X1147036Y523396D01*
G01X1155770D02*
X1151403Y513771D01*
G01X1164536Y505896D02*
Y523396D01*
X1169776D01*
X1171523Y522521D01*
X1172833Y520479D01*
X1173270Y518146D01*
X1172833Y515813D01*
X1171741Y514063D01*
X1169776Y513187D01*
X1164536D01*
G01X1190770Y505896D02*
X1182036D01*
Y523396D01*
X1190770D01*
G01X1187276Y514938D02*
X1182036D01*
G01X1339203Y482912D02*
Y471246D01*
G01Y487579D02*
X1338766Y487871D01*
Y488454D01*
X1339203Y488746D01*
X1339640Y488454D01*
Y487871D01*
X1339203Y487579D01*
G01X1353428Y473287D02*
X1354520Y472121D01*
X1356048Y471246D01*
X1357358D01*
X1358668Y471829D01*
X1359541Y472704D01*
X1359978Y473870D01*
X1359760Y475621D01*
X1358886Y476496D01*
X1354956Y478246D01*
X1354083Y480288D01*
X1354520Y481746D01*
X1355393Y482621D01*
X1356703Y482912D01*
X1358013Y482621D01*
X1359323Y481746D01*
G01X1386681Y471246D02*
Y488746D01*
X1396725Y471246D01*
Y488746D01*
G01X1409203Y471246D02*
X1407456Y471538D01*
X1405928Y472704D01*
X1404618Y474454D01*
X1403744Y476496D01*
X1403308Y478829D01*
Y481163D01*
X1403744Y483496D01*
X1404618Y485538D01*
X1405928Y487287D01*
X1407456Y488454D01*
X1409203Y488746D01*
X1410949Y488454D01*
X1412478Y487287D01*
X1413788Y485538D01*
X1414662Y483496D01*
X1415098Y481163D01*
Y478829D01*
X1414662Y476496D01*
X1413788Y474454D01*
X1412478Y472704D01*
X1410949Y471538D01*
X1409203Y471246D01*
G01X1426703Y488746D02*
Y471246D01*
G01X1421681Y488746D02*
X1431725D01*
G01X1457991Y482912D02*
Y474746D01*
X1458865Y472704D01*
X1460175Y471538D01*
X1461703Y471246D01*
X1463231Y471538D01*
X1464541Y472704D01*
X1465415Y474746D01*
G01Y471246D02*
Y482912D01*
G01X1475928Y473287D02*
X1477020Y472121D01*
X1478548Y471246D01*
X1479858D01*
X1481168Y471829D01*
X1482041Y472704D01*
X1482478Y473870D01*
X1482260Y475621D01*
X1481386Y476496D01*
X1477456Y478246D01*
X1476583Y480288D01*
X1477020Y481746D01*
X1477893Y482621D01*
X1479203Y482912D01*
X1480513Y482621D01*
X1481823Y481746D01*
G01X1493428Y479121D02*
X1500415D01*
X1499760Y481163D01*
X1498668Y482329D01*
X1497140Y482912D01*
X1495611Y482621D01*
X1494301Y481746D01*
X1493428Y479704D01*
X1492991Y477954D01*
Y476204D01*
X1493428Y474454D01*
X1494520Y472704D01*
X1495830Y471538D01*
X1497358Y471246D01*
X1498886Y471829D01*
X1500415Y473579D01*
G01X1518133Y488746D02*
Y471246D01*
G01Y473870D02*
X1517260Y472412D01*
X1515949Y471538D01*
X1514421Y471246D01*
X1512675Y471829D01*
X1511365Y473287D01*
X1510491Y475037D01*
X1510273Y477079D01*
X1510491Y479121D01*
X1511365Y480871D01*
X1512675Y482329D01*
X1514421Y482912D01*
X1515949Y482621D01*
X1517041Y482037D01*
X1518133Y480871D01*
G01X1264400Y505313D02*
X1274006Y518146D01*
G01X1269203Y520479D02*
Y502979D01*
G01X1274006Y505313D02*
X1264400Y518146D01*
G01X1262653Y511729D02*
X1275753D01*
G01X1301365D02*
X1307041D01*
G01X1334400Y505896D02*
Y523396D01*
X1338766D01*
X1340513Y522521D01*
X1341823Y521354D01*
X1342915Y519605D01*
X1343788Y517562D01*
X1344006Y514646D01*
X1343788Y511729D01*
X1342915Y509687D01*
X1341823Y507937D01*
X1340513Y506771D01*
X1338766Y505896D01*
X1334400D01*
G01X1353428Y513771D02*
X1360415D01*
X1359760Y515813D01*
X1358668Y516979D01*
X1357140Y517562D01*
X1355611Y517271D01*
X1354301Y516396D01*
X1353428Y514354D01*
X1352991Y512604D01*
Y510854D01*
X1353428Y509104D01*
X1354520Y507354D01*
X1355830Y506188D01*
X1357358Y505896D01*
X1358886Y506479D01*
X1360415Y508229D01*
G01X1370491Y505896D02*
Y517562D01*
G01Y514646D02*
X1371365Y516104D01*
X1372675Y517271D01*
X1374421Y517562D01*
X1375949Y517271D01*
X1377260Y516104D01*
X1377915Y514063D01*
Y505896D01*
G01X1391703D02*
X1390393Y506188D01*
X1389083Y507354D01*
X1388209Y509396D01*
X1387773Y511729D01*
X1388209Y514063D01*
X1389083Y516104D01*
X1390393Y517271D01*
X1391703Y517562D01*
X1393013Y517271D01*
X1394323Y516104D01*
X1395196Y514063D01*
X1395415Y511729D01*
X1395196Y509396D01*
X1394323Y507354D01*
X1393013Y506188D01*
X1391703Y505896D01*
G01X1409203Y523396D02*
Y505896D01*
G01X1406146Y517562D02*
X1412260D01*
G01X1423428Y513771D02*
X1430415D01*
X1429760Y515813D01*
X1428668Y516979D01*
X1427140Y517562D01*
X1425611Y517271D01*
X1424301Y516396D01*
X1423428Y514354D01*
X1422991Y512604D01*
Y510854D01*
X1423428Y509104D01*
X1424520Y507354D01*
X1425830Y506188D01*
X1427358Y505896D01*
X1428886Y506479D01*
X1430415Y508229D01*
G01X1440928Y507937D02*
X1442020Y506771D01*
X1443548Y505896D01*
X1444858D01*
X1446168Y506479D01*
X1447041Y507354D01*
X1447478Y508520D01*
X1447260Y510271D01*
X1446386Y511146D01*
X1442456Y512896D01*
X1441583Y514938D01*
X1442020Y516396D01*
X1442893Y517271D01*
X1444203Y517562D01*
X1445513Y517271D01*
X1446823Y516396D01*
G01X1479203Y523396D02*
Y505896D01*
G01X1476146Y517562D02*
X1482260D01*
G01X1492991Y505896D02*
Y523396D01*
G01Y514938D02*
X1494083Y516396D01*
X1495175Y517271D01*
X1496921Y517562D01*
X1498231Y517271D01*
X1499760Y516104D01*
X1500415Y514354D01*
Y505896D01*
G01X1518133D02*
Y517562D01*
G01Y515521D02*
X1517260Y516687D01*
X1515949Y517271D01*
X1514421Y517562D01*
X1512893Y516979D01*
X1511583Y515813D01*
X1510709Y514063D01*
X1510273Y511729D01*
X1510709Y509396D01*
X1511583Y507646D01*
X1512893Y506479D01*
X1514421Y505896D01*
X1515949Y506188D01*
X1517260Y507062D01*
X1518133Y508229D01*
G01X1531703Y523396D02*
Y505896D01*
G01X1528646Y517562D02*
X1534760D01*
G01X1566703Y523396D02*
Y505896D01*
G01X1563646Y517562D02*
X1569760D01*
G01X1580491Y505896D02*
Y523396D01*
G01Y514938D02*
X1581583Y516396D01*
X1582675Y517271D01*
X1584421Y517562D01*
X1585731Y517271D01*
X1587260Y516104D01*
X1587915Y514354D01*
Y505896D01*
G01X1601703Y517562D02*
Y505896D01*
G01Y522229D02*
X1601266Y522521D01*
Y523104D01*
X1601703Y523396D01*
X1602140Y523104D01*
Y522521D01*
X1601703Y522229D01*
G01X1615928Y507937D02*
X1617020Y506771D01*
X1618548Y505896D01*
X1619858D01*
X1621168Y506479D01*
X1622041Y507354D01*
X1622478Y508520D01*
X1622260Y510271D01*
X1621386Y511146D01*
X1617456Y512896D01*
X1616583Y514938D01*
X1617020Y516396D01*
X1617893Y517271D01*
X1619203Y517562D01*
X1620513Y517271D01*
X1621823Y516396D01*
G01X1651583Y523396D02*
X1656823D01*
G01X1654203D02*
Y505896D01*
G01X1651583D02*
X1656823D01*
G01X1665153D02*
Y517562D01*
G01Y514354D02*
X1665808Y515813D01*
X1666900Y516979D01*
X1668428Y517562D01*
X1669956Y516979D01*
X1671048Y515813D01*
X1671703Y514354D01*
Y505896D01*
G01Y514354D02*
X1672358Y515813D01*
X1673449Y516979D01*
X1674978Y517562D01*
X1676506Y516979D01*
X1677598Y515813D01*
X1678253Y514063D01*
Y505896D01*
G01X1685273Y500063D02*
Y517562D01*
G01Y514938D02*
X1686365Y516396D01*
X1687456Y517271D01*
X1689203Y517562D01*
X1690731Y517271D01*
X1692260Y515813D01*
X1692915Y513771D01*
X1693133Y511729D01*
X1692915Y509687D01*
X1692260Y507646D01*
X1690949Y506479D01*
X1689203Y505896D01*
X1687675Y506188D01*
X1686146Y507062D01*
X1685273Y508229D01*
G01X1703428Y513771D02*
X1710415D01*
X1709760Y515813D01*
X1708668Y516979D01*
X1707140Y517562D01*
X1705611Y517271D01*
X1704301Y516396D01*
X1703428Y514354D01*
X1702991Y512604D01*
Y510854D01*
X1703428Y509104D01*
X1704520Y507354D01*
X1705830Y506188D01*
X1707358Y505896D01*
X1708886Y506479D01*
X1710415Y508229D01*
G01X1728133Y523396D02*
Y505896D01*
G01Y508520D02*
X1727260Y507062D01*
X1725949Y506188D01*
X1724421Y505896D01*
X1722675Y506479D01*
X1721365Y507937D01*
X1720491Y509687D01*
X1720273Y511729D01*
X1720491Y513771D01*
X1721365Y515521D01*
X1722675Y516979D01*
X1724421Y517562D01*
X1725949Y517271D01*
X1727041Y516687D01*
X1728133Y515521D01*
G01X1745633Y505896D02*
Y517562D01*
G01Y515521D02*
X1744760Y516687D01*
X1743449Y517271D01*
X1741921Y517562D01*
X1740393Y516979D01*
X1739083Y515813D01*
X1738209Y514063D01*
X1737773Y511729D01*
X1738209Y509396D01*
X1739083Y507646D01*
X1740393Y506479D01*
X1741921Y505896D01*
X1743449Y506188D01*
X1744760Y507062D01*
X1745633Y508229D01*
G01X1755491Y505896D02*
Y517562D01*
G01Y514646D02*
X1756365Y516104D01*
X1757675Y517271D01*
X1759421Y517562D01*
X1760949Y517271D01*
X1762260Y516104D01*
X1762915Y514063D01*
Y505896D01*
G01X1780196Y516104D02*
X1778668Y517271D01*
X1777358Y517562D01*
X1775611Y516979D01*
X1774301Y515813D01*
X1773428Y513771D01*
X1773209Y511729D01*
X1773428Y509687D01*
X1774301Y507937D01*
X1775611Y506479D01*
X1777358Y505896D01*
X1778886Y506479D01*
X1780196Y507646D01*
G01X1790928Y513771D02*
X1797915D01*
X1797260Y515813D01*
X1796168Y516979D01*
X1794640Y517562D01*
X1793111Y517271D01*
X1791801Y516396D01*
X1790928Y514354D01*
X1790491Y512604D01*
Y510854D01*
X1790928Y509104D01*
X1792020Y507354D01*
X1793330Y506188D01*
X1794858Y505896D01*
X1796386Y506479D01*
X1797915Y508229D01*
M02*
